FILE_TYPE = MACRO_DRAWING;
SET COLOR_WIRE YELLOW;
SET COLOR_PROP ORANGE;
SET COLOR_DOT WHITE;
SET COLOR_ARC YELLOW;
SET COLOR_BODY GREEN;
SET COLOR_NOTE PURPLE;
SET PROP_DISPLAY VALUE;
SET PAGE_NUMBER P95;
FORCEADD OFFPAGE..6
(-8325 3575);
FORCEPROP 2 LAST $XR0 20 
J 0
(-8574 3575);
DISPLAY 0.638298 (-8574 3575);
PAINT MONO (-8574 3575);
FORCEPROP 2 LAST CDS_LIB mstr_standard
J 0
(-8325 3575);
DISPLAY 0.723404 (-8325 3575);
PAINT MONO (-8325 3575);
DISPLAY INVISIBLE (-8325 3575);
FORCEPROP 1 LAST OFFPAGE TRUE
J 0
(-8000 3450);
DISPLAY 0.872340 (-8000 3450);
PAINT GREEN (-8000 3450);
DISPLAY INVISIBLE (-8000 3450);
FORCEPROP 1 LAST COMMENT_BODY TRUE
J 0
(-8225 3500);
DISPLAY 0.872340 (-8225 3500);
PAINT GREEN (-8225 3500);
DISPLAY INVISIBLE (-8225 3500);
FORCEPROP 2 LAST PATH I10
J 0
(-8275 3650);
DISPLAY 1.021277 (-8275 3650);
DISPLAY INVISIBLE (-8275 3650);
FORCEADD TAP..1
(-6025 4125);
FORCEPROP 3 LASTPIN (-6075 4125) SIG_NAME M_K_CPU0_SA_DQ<6>
J 0
(-6065 4135);
DISPLAY 0.659574 (-6065 4135);
PAINT MONO (-6065 4135);
DISPLAY INVISIBLE (-6065 4135);
FORCEPROP 1 LASTPIN (-6075 4125) BN 6
J 0
(-6087 4133);
DISPLAY 0.489362 (-6087 4133);
PAINT GREEN (-6087 4133);
FORCEPROP 2 LAST CDS_LIB mstr_standard
J 0
(-6025 4125);
DISPLAY 0.723404 (-6025 4125);
PAINT MONO (-6025 4125);
DISPLAY INVISIBLE (-6025 4125);
FORCEPROP 1 LAST BODY_TYPE PLUMBING
J 0
(-6025 4175);
DISPLAY 0.872340 (-6025 4175);
PAINT GREEN (-6025 4175);
DISPLAY INVISIBLE (-6025 4175);
FORCEPROP 1 LAST HDL_TAP TRUE
J 0
(-5700 4000);
DISPLAY 0.872340 (-5700 4000);
DISPLAY INVISIBLE (-5700 4000);
FORCEPROP 1 LAST PATH I100
J 0
(-6027 4125);
DISPLAY 0.872340 (-6027 4125);
PAINT GREEN (-6027 4125);
DISPLAY INVISIBLE (-6027 4125);
FORCEADD TAP..1
(-6025 4175);
FORCEPROP 3 LASTPIN (-6075 4175) SIG_NAME M_K_CPU0_SA_DQ<7>
J 0
(-6065 4185);
DISPLAY 0.659574 (-6065 4185);
PAINT MONO (-6065 4185);
DISPLAY INVISIBLE (-6065 4185);
FORCEPROP 1 LASTPIN (-6075 4175) BN 7
J 0
(-6087 4183);
DISPLAY 0.489362 (-6087 4183);
PAINT GREEN (-6087 4183);
FORCEPROP 2 LAST CDS_LIB mstr_standard
J 0
(-6025 4175);
DISPLAY 0.723404 (-6025 4175);
PAINT MONO (-6025 4175);
DISPLAY INVISIBLE (-6025 4175);
FORCEPROP 1 LAST BODY_TYPE PLUMBING
J 0
(-6025 4225);
DISPLAY 0.872340 (-6025 4225);
PAINT GREEN (-6025 4225);
DISPLAY INVISIBLE (-6025 4225);
FORCEPROP 1 LAST HDL_TAP TRUE
J 0
(-5700 4050);
DISPLAY 0.872340 (-5700 4050);
DISPLAY INVISIBLE (-5700 4050);
FORCEPROP 1 LAST PATH I101
J 0
(-6027 4175);
DISPLAY 0.872340 (-6027 4175);
PAINT GREEN (-6027 4175);
DISPLAY INVISIBLE (-6027 4175);
FORCEADD TAP..1
(-6025 4225);
FORCEPROP 3 LASTPIN (-6075 4225) SIG_NAME M_K_CPU0_SA_DQ<8>
J 0
(-6065 4235);
DISPLAY 0.659574 (-6065 4235);
PAINT MONO (-6065 4235);
DISPLAY INVISIBLE (-6065 4235);
FORCEPROP 1 LASTPIN (-6075 4225) BN 8
J 0
(-6087 4233);
DISPLAY 0.489362 (-6087 4233);
PAINT GREEN (-6087 4233);
FORCEPROP 2 LAST CDS_LIB mstr_standard
J 0
(-6025 4225);
DISPLAY 0.723404 (-6025 4225);
PAINT MONO (-6025 4225);
DISPLAY INVISIBLE (-6025 4225);
FORCEPROP 1 LAST BODY_TYPE PLUMBING
J 0
(-6025 4275);
DISPLAY 0.872340 (-6025 4275);
PAINT GREEN (-6025 4275);
DISPLAY INVISIBLE (-6025 4275);
FORCEPROP 1 LAST HDL_TAP TRUE
J 0
(-5700 4100);
DISPLAY 0.872340 (-5700 4100);
DISPLAY INVISIBLE (-5700 4100);
FORCEPROP 1 LAST PATH I102
J 0
(-6027 4225);
DISPLAY 0.872340 (-6027 4225);
PAINT GREEN (-6027 4225);
DISPLAY INVISIBLE (-6027 4225);
FORCEADD TAP..1
(-6025 4275);
FORCEPROP 3 LASTPIN (-6075 4275) SIG_NAME M_K_CPU0_SA_DQ<9>
J 0
(-6065 4285);
DISPLAY 0.659574 (-6065 4285);
PAINT MONO (-6065 4285);
DISPLAY INVISIBLE (-6065 4285);
FORCEPROP 1 LASTPIN (-6075 4275) BN 9
J 0
(-6087 4283);
DISPLAY 0.489362 (-6087 4283);
PAINT GREEN (-6087 4283);
FORCEPROP 2 LAST CDS_LIB mstr_standard
J 0
(-6025 4275);
DISPLAY 0.723404 (-6025 4275);
PAINT MONO (-6025 4275);
DISPLAY INVISIBLE (-6025 4275);
FORCEPROP 1 LAST BODY_TYPE PLUMBING
J 0
(-6025 4325);
DISPLAY 0.872340 (-6025 4325);
PAINT GREEN (-6025 4325);
DISPLAY INVISIBLE (-6025 4325);
FORCEPROP 1 LAST HDL_TAP TRUE
J 0
(-5700 4150);
DISPLAY 0.872340 (-5700 4150);
DISPLAY INVISIBLE (-5700 4150);
FORCEPROP 1 LAST PATH I103
J 0
(-6027 4275);
DISPLAY 0.872340 (-6027 4275);
PAINT GREEN (-6027 4275);
DISPLAY INVISIBLE (-6027 4275);
FORCEADD TAP..1
(-6025 4325);
FORCEPROP 3 LASTPIN (-6075 4325) SIG_NAME M_K_CPU0_SA_DQ<10>
J 0
(-6065 4335);
DISPLAY 0.659574 (-6065 4335);
PAINT MONO (-6065 4335);
DISPLAY INVISIBLE (-6065 4335);
FORCEPROP 1 LASTPIN (-6075 4325) BN 10
J 0
(-6087 4333);
DISPLAY 0.489362 (-6087 4333);
PAINT GREEN (-6087 4333);
FORCEPROP 2 LAST CDS_LIB mstr_standard
J 0
(-6025 4325);
DISPLAY 0.723404 (-6025 4325);
PAINT MONO (-6025 4325);
DISPLAY INVISIBLE (-6025 4325);
FORCEPROP 1 LAST BODY_TYPE PLUMBING
J 0
(-6025 4375);
DISPLAY 0.872340 (-6025 4375);
PAINT GREEN (-6025 4375);
DISPLAY INVISIBLE (-6025 4375);
FORCEPROP 1 LAST HDL_TAP TRUE
J 0
(-5700 4200);
DISPLAY 0.872340 (-5700 4200);
DISPLAY INVISIBLE (-5700 4200);
FORCEPROP 1 LAST PATH I104
J 0
(-6027 4325);
DISPLAY 0.872340 (-6027 4325);
PAINT GREEN (-6027 4325);
DISPLAY INVISIBLE (-6027 4325);
FORCEADD TAP..1
(-6025 4425);
FORCEPROP 3 LASTPIN (-6075 4425) SIG_NAME M_K_CPU0_SA_DQ<12>
J 0
(-6065 4435);
DISPLAY 0.659574 (-6065 4435);
PAINT MONO (-6065 4435);
DISPLAY INVISIBLE (-6065 4435);
FORCEPROP 1 LASTPIN (-6075 4425) BN 12
J 0
(-6087 4433);
DISPLAY 0.489362 (-6087 4433);
PAINT GREEN (-6087 4433);
FORCEPROP 2 LAST CDS_LIB mstr_standard
J 0
(-6025 4425);
DISPLAY 0.723404 (-6025 4425);
PAINT MONO (-6025 4425);
DISPLAY INVISIBLE (-6025 4425);
FORCEPROP 1 LAST BODY_TYPE PLUMBING
J 0
(-6025 4475);
DISPLAY 0.872340 (-6025 4475);
PAINT GREEN (-6025 4475);
DISPLAY INVISIBLE (-6025 4475);
FORCEPROP 1 LAST HDL_TAP TRUE
J 0
(-5700 4300);
DISPLAY 0.872340 (-5700 4300);
DISPLAY INVISIBLE (-5700 4300);
FORCEPROP 1 LAST PATH I105
J 0
(-6027 4425);
DISPLAY 0.872340 (-6027 4425);
PAINT GREEN (-6027 4425);
DISPLAY INVISIBLE (-6027 4425);
FORCEADD TAP..1
(-6025 4375);
FORCEPROP 3 LASTPIN (-6075 4375) SIG_NAME M_K_CPU0_SA_DQ<11>
J 0
(-6065 4385);
DISPLAY 0.659574 (-6065 4385);
PAINT MONO (-6065 4385);
DISPLAY INVISIBLE (-6065 4385);
FORCEPROP 1 LASTPIN (-6075 4375) BN 11
J 0
(-6087 4383);
DISPLAY 0.489362 (-6087 4383);
PAINT GREEN (-6087 4383);
FORCEPROP 2 LAST CDS_LIB mstr_standard
J 0
(-6025 4375);
DISPLAY 0.723404 (-6025 4375);
PAINT MONO (-6025 4375);
DISPLAY INVISIBLE (-6025 4375);
FORCEPROP 1 LAST BODY_TYPE PLUMBING
J 0
(-6025 4425);
DISPLAY 0.872340 (-6025 4425);
PAINT GREEN (-6025 4425);
DISPLAY INVISIBLE (-6025 4425);
FORCEPROP 1 LAST HDL_TAP TRUE
J 0
(-5700 4250);
DISPLAY 0.872340 (-5700 4250);
DISPLAY INVISIBLE (-5700 4250);
FORCEPROP 1 LAST PATH I106
J 0
(-6027 4375);
DISPLAY 0.872340 (-6027 4375);
PAINT GREEN (-6027 4375);
DISPLAY INVISIBLE (-6027 4375);
FORCEADD TAP..1
(-6025 4475);
FORCEPROP 3 LASTPIN (-6075 4475) SIG_NAME M_K_CPU0_SA_DQ<13>
J 0
(-6065 4485);
DISPLAY 0.659574 (-6065 4485);
PAINT MONO (-6065 4485);
DISPLAY INVISIBLE (-6065 4485);
FORCEPROP 1 LASTPIN (-6075 4475) BN 13
J 0
(-6087 4483);
DISPLAY 0.489362 (-6087 4483);
PAINT GREEN (-6087 4483);
FORCEPROP 2 LAST CDS_LIB mstr_standard
J 0
(-6025 4475);
DISPLAY 0.723404 (-6025 4475);
PAINT MONO (-6025 4475);
DISPLAY INVISIBLE (-6025 4475);
FORCEPROP 1 LAST BODY_TYPE PLUMBING
J 0
(-6025 4525);
DISPLAY 0.872340 (-6025 4525);
PAINT GREEN (-6025 4525);
DISPLAY INVISIBLE (-6025 4525);
FORCEPROP 1 LAST HDL_TAP TRUE
J 0
(-5700 4350);
DISPLAY 0.872340 (-5700 4350);
DISPLAY INVISIBLE (-5700 4350);
FORCEPROP 1 LAST PATH I107
J 0
(-6027 4475);
DISPLAY 0.872340 (-6027 4475);
PAINT GREEN (-6027 4475);
DISPLAY INVISIBLE (-6027 4475);
FORCEADD TAP..1
(-6025 4525);
FORCEPROP 3 LASTPIN (-6075 4525) SIG_NAME M_K_CPU0_SA_DQ<14>
J 0
(-6065 4535);
DISPLAY 0.659574 (-6065 4535);
PAINT MONO (-6065 4535);
DISPLAY INVISIBLE (-6065 4535);
FORCEPROP 1 LASTPIN (-6075 4525) BN 14
J 0
(-6087 4533);
DISPLAY 0.489362 (-6087 4533);
PAINT GREEN (-6087 4533);
FORCEPROP 2 LAST CDS_LIB mstr_standard
J 0
(-6025 4525);
DISPLAY 0.723404 (-6025 4525);
PAINT MONO (-6025 4525);
DISPLAY INVISIBLE (-6025 4525);
FORCEPROP 1 LAST BODY_TYPE PLUMBING
J 0
(-6025 4575);
DISPLAY 0.872340 (-6025 4575);
PAINT GREEN (-6025 4575);
DISPLAY INVISIBLE (-6025 4575);
FORCEPROP 1 LAST HDL_TAP TRUE
J 0
(-5700 4400);
DISPLAY 0.872340 (-5700 4400);
DISPLAY INVISIBLE (-5700 4400);
FORCEPROP 1 LAST PATH I108
J 0
(-6027 4525);
DISPLAY 0.872340 (-6027 4525);
PAINT GREEN (-6027 4525);
DISPLAY INVISIBLE (-6027 4525);
FORCEADD TAP..1
(-6025 4575);
FORCEPROP 3 LASTPIN (-6075 4575) SIG_NAME M_K_CPU0_SA_DQ<15>
J 0
(-6065 4585);
DISPLAY 0.659574 (-6065 4585);
PAINT MONO (-6065 4585);
DISPLAY INVISIBLE (-6065 4585);
FORCEPROP 1 LASTPIN (-6075 4575) BN 15
J 0
(-6087 4583);
DISPLAY 0.489362 (-6087 4583);
PAINT GREEN (-6087 4583);
FORCEPROP 2 LAST CDS_LIB mstr_standard
J 0
(-6025 4575);
DISPLAY 0.723404 (-6025 4575);
PAINT MONO (-6025 4575);
DISPLAY INVISIBLE (-6025 4575);
FORCEPROP 1 LAST BODY_TYPE PLUMBING
J 0
(-6025 4625);
DISPLAY 0.872340 (-6025 4625);
PAINT GREEN (-6025 4625);
DISPLAY INVISIBLE (-6025 4625);
FORCEPROP 1 LAST HDL_TAP TRUE
J 0
(-5700 4450);
DISPLAY 0.872340 (-5700 4450);
DISPLAY INVISIBLE (-5700 4450);
FORCEPROP 1 LAST PATH I109
J 0
(-6027 4575);
DISPLAY 0.872340 (-6027 4575);
PAINT GREEN (-6027 4575);
DISPLAY INVISIBLE (-6027 4575);
FORCEADD OFFPAGE..1
(-8325 4125);
FORCEPROP 2 LAST $XR0 20 
J 0
(-8546 4125);
DISPLAY 0.638298 (-8546 4125);
PAINT MONO (-8546 4125);
FORCEPROP 2 LAST CDS_LIB mstr_standard
J 0
(-8325 4125);
DISPLAY 0.723404 (-8325 4125);
PAINT MONO (-8325 4125);
DISPLAY INVISIBLE (-8325 4125);
FORCEPROP 1 LAST OFFPAGE TRUE
J 0
(-8000 4000);
DISPLAY 0.872340 (-8000 4000);
PAINT GREEN (-8000 4000);
DISPLAY INVISIBLE (-8000 4000);
FORCEPROP 1 LAST COMMENT_BODY TRUE
J 0
(-8200 4025);
DISPLAY 0.872340 (-8200 4025);
PAINT GREEN (-8200 4025);
DISPLAY INVISIBLE (-8200 4025);
FORCEPROP 2 LAST PATH I11
J 0
(-8275 4200);
DISPLAY 1.021277 (-8275 4200);
DISPLAY INVISIBLE (-8275 4200);
FORCEADD TAP..1
(-6025 4625);
FORCEPROP 3 LASTPIN (-6075 4625) SIG_NAME M_K_CPU0_SA_DQ<16>
J 0
(-6065 4635);
DISPLAY 0.659574 (-6065 4635);
PAINT MONO (-6065 4635);
DISPLAY INVISIBLE (-6065 4635);
FORCEPROP 1 LASTPIN (-6075 4625) BN 16
J 0
(-6087 4633);
DISPLAY 0.489362 (-6087 4633);
PAINT GREEN (-6087 4633);
FORCEPROP 2 LAST CDS_LIB mstr_standard
J 0
(-6025 4625);
DISPLAY 0.723404 (-6025 4625);
PAINT MONO (-6025 4625);
DISPLAY INVISIBLE (-6025 4625);
FORCEPROP 1 LAST BODY_TYPE PLUMBING
J 0
(-6025 4675);
DISPLAY 0.872340 (-6025 4675);
PAINT GREEN (-6025 4675);
DISPLAY INVISIBLE (-6025 4675);
FORCEPROP 1 LAST HDL_TAP TRUE
J 0
(-5700 4500);
DISPLAY 0.872340 (-5700 4500);
DISPLAY INVISIBLE (-5700 4500);
FORCEPROP 1 LAST PATH I110
J 0
(-6027 4625);
DISPLAY 0.872340 (-6027 4625);
PAINT GREEN (-6027 4625);
DISPLAY INVISIBLE (-6027 4625);
FORCEADD TAP..1
(-6025 4675);
FORCEPROP 3 LASTPIN (-6075 4675) SIG_NAME M_K_CPU0_SA_DQ<17>
J 0
(-6065 4685);
DISPLAY 0.659574 (-6065 4685);
PAINT MONO (-6065 4685);
DISPLAY INVISIBLE (-6065 4685);
FORCEPROP 1 LASTPIN (-6075 4675) BN 17
J 0
(-6087 4683);
DISPLAY 0.489362 (-6087 4683);
PAINT GREEN (-6087 4683);
FORCEPROP 2 LAST CDS_LIB mstr_standard
J 0
(-6025 4675);
DISPLAY 0.723404 (-6025 4675);
PAINT MONO (-6025 4675);
DISPLAY INVISIBLE (-6025 4675);
FORCEPROP 1 LAST BODY_TYPE PLUMBING
J 0
(-6025 4725);
DISPLAY 0.872340 (-6025 4725);
PAINT GREEN (-6025 4725);
DISPLAY INVISIBLE (-6025 4725);
FORCEPROP 1 LAST HDL_TAP TRUE
J 0
(-5700 4550);
DISPLAY 0.872340 (-5700 4550);
DISPLAY INVISIBLE (-5700 4550);
FORCEPROP 1 LAST PATH I111
J 0
(-6027 4675);
DISPLAY 0.872340 (-6027 4675);
PAINT GREEN (-6027 4675);
DISPLAY INVISIBLE (-6027 4675);
FORCEADD TAP..1
(-6025 4725);
FORCEPROP 3 LASTPIN (-6075 4725) SIG_NAME M_K_CPU0_SA_DQ<18>
J 0
(-6065 4735);
DISPLAY 0.659574 (-6065 4735);
PAINT MONO (-6065 4735);
DISPLAY INVISIBLE (-6065 4735);
FORCEPROP 1 LASTPIN (-6075 4725) BN 18
J 0
(-6087 4733);
DISPLAY 0.489362 (-6087 4733);
PAINT GREEN (-6087 4733);
FORCEPROP 2 LAST CDS_LIB mstr_standard
J 0
(-6025 4725);
DISPLAY 0.723404 (-6025 4725);
PAINT MONO (-6025 4725);
DISPLAY INVISIBLE (-6025 4725);
FORCEPROP 1 LAST BODY_TYPE PLUMBING
J 0
(-6025 4775);
DISPLAY 0.872340 (-6025 4775);
PAINT GREEN (-6025 4775);
DISPLAY INVISIBLE (-6025 4775);
FORCEPROP 1 LAST HDL_TAP TRUE
J 0
(-5700 4600);
DISPLAY 0.872340 (-5700 4600);
DISPLAY INVISIBLE (-5700 4600);
FORCEPROP 1 LAST PATH I112
J 0
(-6027 4725);
DISPLAY 0.872340 (-6027 4725);
PAINT GREEN (-6027 4725);
DISPLAY INVISIBLE (-6027 4725);
FORCEADD TAP..1
(-6025 4775);
FORCEPROP 3 LASTPIN (-6075 4775) SIG_NAME M_K_CPU0_SA_DQ<19>
J 0
(-6065 4785);
DISPLAY 0.659574 (-6065 4785);
PAINT MONO (-6065 4785);
DISPLAY INVISIBLE (-6065 4785);
FORCEPROP 1 LASTPIN (-6075 4775) BN 19
J 0
(-6087 4783);
DISPLAY 0.489362 (-6087 4783);
PAINT GREEN (-6087 4783);
FORCEPROP 2 LAST CDS_LIB mstr_standard
J 0
(-6025 4775);
DISPLAY 0.723404 (-6025 4775);
PAINT MONO (-6025 4775);
DISPLAY INVISIBLE (-6025 4775);
FORCEPROP 1 LAST BODY_TYPE PLUMBING
J 0
(-6025 4825);
DISPLAY 0.872340 (-6025 4825);
PAINT GREEN (-6025 4825);
DISPLAY INVISIBLE (-6025 4825);
FORCEPROP 1 LAST HDL_TAP TRUE
J 0
(-5700 4650);
DISPLAY 0.872340 (-5700 4650);
DISPLAY INVISIBLE (-5700 4650);
FORCEPROP 1 LAST PATH I113
J 0
(-6027 4775);
DISPLAY 0.872340 (-6027 4775);
PAINT GREEN (-6027 4775);
DISPLAY INVISIBLE (-6027 4775);
FORCEADD TAP..1
(-6025 4825);
FORCEPROP 3 LASTPIN (-6075 4825) SIG_NAME M_K_CPU0_SA_DQ<20>
J 0
(-6065 4835);
DISPLAY 0.659574 (-6065 4835);
PAINT MONO (-6065 4835);
DISPLAY INVISIBLE (-6065 4835);
FORCEPROP 1 LASTPIN (-6075 4825) BN 20
J 0
(-6087 4833);
DISPLAY 0.489362 (-6087 4833);
PAINT GREEN (-6087 4833);
FORCEPROP 2 LAST CDS_LIB mstr_standard
J 0
(-6025 4825);
DISPLAY 0.723404 (-6025 4825);
PAINT MONO (-6025 4825);
DISPLAY INVISIBLE (-6025 4825);
FORCEPROP 1 LAST BODY_TYPE PLUMBING
J 0
(-6025 4875);
DISPLAY 0.872340 (-6025 4875);
PAINT GREEN (-6025 4875);
DISPLAY INVISIBLE (-6025 4875);
FORCEPROP 1 LAST HDL_TAP TRUE
J 0
(-5700 4700);
DISPLAY 0.872340 (-5700 4700);
DISPLAY INVISIBLE (-5700 4700);
FORCEPROP 1 LAST PATH I114
J 0
(-6027 4825);
DISPLAY 0.872340 (-6027 4825);
PAINT GREEN (-6027 4825);
DISPLAY INVISIBLE (-6027 4825);
FORCEADD TAP..1
(-6025 4875);
FORCEPROP 3 LASTPIN (-6075 4875) SIG_NAME M_K_CPU0_SA_DQ<21>
J 0
(-6065 4885);
DISPLAY 0.659574 (-6065 4885);
PAINT MONO (-6065 4885);
DISPLAY INVISIBLE (-6065 4885);
FORCEPROP 1 LASTPIN (-6075 4875) BN 21
J 0
(-6087 4883);
DISPLAY 0.489362 (-6087 4883);
PAINT GREEN (-6087 4883);
FORCEPROP 2 LAST CDS_LIB mstr_standard
J 0
(-6025 4875);
DISPLAY 0.723404 (-6025 4875);
PAINT MONO (-6025 4875);
DISPLAY INVISIBLE (-6025 4875);
FORCEPROP 1 LAST BODY_TYPE PLUMBING
J 0
(-6025 4925);
DISPLAY 0.872340 (-6025 4925);
PAINT GREEN (-6025 4925);
DISPLAY INVISIBLE (-6025 4925);
FORCEPROP 1 LAST HDL_TAP TRUE
J 0
(-5700 4750);
DISPLAY 0.872340 (-5700 4750);
DISPLAY INVISIBLE (-5700 4750);
FORCEPROP 1 LAST PATH I115
J 0
(-6027 4875);
DISPLAY 0.872340 (-6027 4875);
PAINT GREEN (-6027 4875);
DISPLAY INVISIBLE (-6027 4875);
FORCEADD TAP..1
(-6025 4925);
FORCEPROP 3 LASTPIN (-6075 4925) SIG_NAME M_K_CPU0_SA_DQ<22>
J 0
(-6065 4935);
DISPLAY 0.659574 (-6065 4935);
PAINT MONO (-6065 4935);
DISPLAY INVISIBLE (-6065 4935);
FORCEPROP 1 LASTPIN (-6075 4925) BN 22
J 0
(-6087 4933);
DISPLAY 0.489362 (-6087 4933);
PAINT GREEN (-6087 4933);
FORCEPROP 2 LAST CDS_LIB mstr_standard
J 0
(-6025 4925);
DISPLAY 0.723404 (-6025 4925);
PAINT MONO (-6025 4925);
DISPLAY INVISIBLE (-6025 4925);
FORCEPROP 1 LAST BODY_TYPE PLUMBING
J 0
(-6025 4975);
DISPLAY 0.872340 (-6025 4975);
PAINT GREEN (-6025 4975);
DISPLAY INVISIBLE (-6025 4975);
FORCEPROP 1 LAST HDL_TAP TRUE
J 0
(-5700 4800);
DISPLAY 0.872340 (-5700 4800);
DISPLAY INVISIBLE (-5700 4800);
FORCEPROP 1 LAST PATH I116
J 0
(-6027 4925);
DISPLAY 0.872340 (-6027 4925);
PAINT GREEN (-6027 4925);
DISPLAY INVISIBLE (-6027 4925);
FORCEADD TAP..1
(-6025 4975);
FORCEPROP 3 LASTPIN (-6075 4975) SIG_NAME M_K_CPU0_SA_DQ<23>
J 0
(-6065 4985);
DISPLAY 0.659574 (-6065 4985);
PAINT MONO (-6065 4985);
DISPLAY INVISIBLE (-6065 4985);
FORCEPROP 1 LASTPIN (-6075 4975) BN 23
J 0
(-6087 4983);
DISPLAY 0.489362 (-6087 4983);
PAINT GREEN (-6087 4983);
FORCEPROP 2 LAST CDS_LIB mstr_standard
J 0
(-6025 4975);
DISPLAY 0.723404 (-6025 4975);
PAINT MONO (-6025 4975);
DISPLAY INVISIBLE (-6025 4975);
FORCEPROP 1 LAST BODY_TYPE PLUMBING
J 0
(-6025 5025);
DISPLAY 0.872340 (-6025 5025);
PAINT GREEN (-6025 5025);
DISPLAY INVISIBLE (-6025 5025);
FORCEPROP 1 LAST HDL_TAP TRUE
J 0
(-5700 4850);
DISPLAY 0.872340 (-5700 4850);
DISPLAY INVISIBLE (-5700 4850);
FORCEPROP 1 LAST PATH I117
J 0
(-6027 4975);
DISPLAY 0.872340 (-6027 4975);
PAINT GREEN (-6027 4975);
DISPLAY INVISIBLE (-6027 4975);
FORCEADD TAP..1
(-6025 5025);
FORCEPROP 3 LASTPIN (-6075 5025) SIG_NAME M_K_CPU0_SA_DQ<24>
J 0
(-6065 5035);
DISPLAY 0.659574 (-6065 5035);
PAINT MONO (-6065 5035);
DISPLAY INVISIBLE (-6065 5035);
FORCEPROP 1 LASTPIN (-6075 5025) BN 24
J 0
(-6087 5033);
DISPLAY 0.489362 (-6087 5033);
PAINT GREEN (-6087 5033);
FORCEPROP 2 LAST CDS_LIB mstr_standard
J 0
(-6025 5025);
DISPLAY 0.723404 (-6025 5025);
PAINT MONO (-6025 5025);
DISPLAY INVISIBLE (-6025 5025);
FORCEPROP 1 LAST BODY_TYPE PLUMBING
J 0
(-6025 5075);
DISPLAY 0.872340 (-6025 5075);
PAINT GREEN (-6025 5075);
DISPLAY INVISIBLE (-6025 5075);
FORCEPROP 1 LAST HDL_TAP TRUE
J 0
(-5700 4900);
DISPLAY 0.872340 (-5700 4900);
DISPLAY INVISIBLE (-5700 4900);
FORCEPROP 1 LAST PATH I118
J 0
(-6027 5025);
DISPLAY 0.872340 (-6027 5025);
PAINT GREEN (-6027 5025);
DISPLAY INVISIBLE (-6027 5025);
FORCEADD TAP..1
(-6025 5075);
FORCEPROP 3 LASTPIN (-6075 5075) SIG_NAME M_K_CPU0_SA_DQ<25>
J 0
(-6065 5085);
DISPLAY 0.659574 (-6065 5085);
PAINT MONO (-6065 5085);
DISPLAY INVISIBLE (-6065 5085);
FORCEPROP 1 LASTPIN (-6075 5075) BN 25
J 0
(-6087 5083);
DISPLAY 0.489362 (-6087 5083);
PAINT GREEN (-6087 5083);
FORCEPROP 2 LAST CDS_LIB mstr_standard
J 0
(-6025 5075);
DISPLAY 0.723404 (-6025 5075);
PAINT MONO (-6025 5075);
DISPLAY INVISIBLE (-6025 5075);
FORCEPROP 1 LAST BODY_TYPE PLUMBING
J 0
(-6025 5125);
DISPLAY 0.872340 (-6025 5125);
PAINT GREEN (-6025 5125);
DISPLAY INVISIBLE (-6025 5125);
FORCEPROP 1 LAST HDL_TAP TRUE
J 0
(-5700 4950);
DISPLAY 0.872340 (-5700 4950);
DISPLAY INVISIBLE (-5700 4950);
FORCEPROP 1 LAST PATH I119
J 0
(-6027 5075);
DISPLAY 0.872340 (-6027 5075);
PAINT GREEN (-6027 5075);
DISPLAY INVISIBLE (-6027 5075);
FORCEADD OFFPAGE..1
(-8325 4075);
FORCEPROP 2 LAST $XR0 20 
J 0
(-8546 4075);
DISPLAY 0.638298 (-8546 4075);
PAINT MONO (-8546 4075);
FORCEPROP 2 LAST CDS_LIB mstr_standard
J 0
(-8325 4075);
DISPLAY 0.808511 (-8325 4075);
DISPLAY INVISIBLE (-8325 4075);
FORCEPROP 1 LAST OFFPAGE TRUE
J 0
(-8000 3950);
DISPLAY 0.872340 (-8000 3950);
PAINT GREEN (-8000 3950);
DISPLAY INVISIBLE (-8000 3950);
FORCEPROP 1 LAST COMMENT_BODY TRUE
J 0
(-8200 3975);
DISPLAY 0.872340 (-8200 3975);
PAINT GREEN (-8200 3975);
DISPLAY INVISIBLE (-8200 3975);
FORCEPROP 2 LAST PATH I12
J 0
(-8275 4150);
DISPLAY 1.021277 (-8275 4150);
DISPLAY INVISIBLE (-8275 4150);
FORCEADD TAP..1
(-6025 5125);
FORCEPROP 3 LASTPIN (-6075 5125) SIG_NAME M_K_CPU0_SA_DQ<26>
J 0
(-6065 5135);
DISPLAY 0.659574 (-6065 5135);
PAINT MONO (-6065 5135);
DISPLAY INVISIBLE (-6065 5135);
FORCEPROP 1 LASTPIN (-6075 5125) BN 26
J 0
(-6087 5133);
DISPLAY 0.489362 (-6087 5133);
PAINT GREEN (-6087 5133);
FORCEPROP 2 LAST CDS_LIB mstr_standard
J 0
(-6025 5125);
DISPLAY 0.723404 (-6025 5125);
PAINT MONO (-6025 5125);
DISPLAY INVISIBLE (-6025 5125);
FORCEPROP 1 LAST BODY_TYPE PLUMBING
J 0
(-6025 5175);
DISPLAY 0.872340 (-6025 5175);
PAINT GREEN (-6025 5175);
DISPLAY INVISIBLE (-6025 5175);
FORCEPROP 1 LAST HDL_TAP TRUE
J 0
(-5700 5000);
DISPLAY 0.872340 (-5700 5000);
DISPLAY INVISIBLE (-5700 5000);
FORCEPROP 1 LAST PATH I120
J 0
(-6027 5125);
DISPLAY 0.872340 (-6027 5125);
PAINT GREEN (-6027 5125);
DISPLAY INVISIBLE (-6027 5125);
FORCEADD TAP..1
(-6025 5175);
FORCEPROP 3 LASTPIN (-6075 5175) SIG_NAME M_K_CPU0_SA_DQ<27>
J 0
(-6065 5185);
DISPLAY 0.659574 (-6065 5185);
PAINT MONO (-6065 5185);
DISPLAY INVISIBLE (-6065 5185);
FORCEPROP 1 LASTPIN (-6075 5175) BN 27
J 0
(-6087 5183);
DISPLAY 0.489362 (-6087 5183);
PAINT GREEN (-6087 5183);
FORCEPROP 2 LAST CDS_LIB mstr_standard
J 0
(-6025 5175);
DISPLAY 0.723404 (-6025 5175);
PAINT MONO (-6025 5175);
DISPLAY INVISIBLE (-6025 5175);
FORCEPROP 1 LAST BODY_TYPE PLUMBING
J 0
(-6025 5225);
DISPLAY 0.872340 (-6025 5225);
PAINT GREEN (-6025 5225);
DISPLAY INVISIBLE (-6025 5225);
FORCEPROP 1 LAST HDL_TAP TRUE
J 0
(-5700 5050);
DISPLAY 0.872340 (-5700 5050);
DISPLAY INVISIBLE (-5700 5050);
FORCEPROP 1 LAST PATH I121
J 0
(-6027 5175);
DISPLAY 0.872340 (-6027 5175);
PAINT GREEN (-6027 5175);
DISPLAY INVISIBLE (-6027 5175);
FORCEADD TAP..1
(-6025 5225);
FORCEPROP 3 LASTPIN (-6075 5225) SIG_NAME M_K_CPU0_SA_DQ<28>
J 0
(-6065 5235);
DISPLAY 0.659574 (-6065 5235);
PAINT MONO (-6065 5235);
DISPLAY INVISIBLE (-6065 5235);
FORCEPROP 1 LASTPIN (-6075 5225) BN 28
J 0
(-6087 5233);
DISPLAY 0.489362 (-6087 5233);
PAINT GREEN (-6087 5233);
FORCEPROP 2 LAST CDS_LIB mstr_standard
J 0
(-6025 5225);
DISPLAY 0.723404 (-6025 5225);
PAINT MONO (-6025 5225);
DISPLAY INVISIBLE (-6025 5225);
FORCEPROP 1 LAST BODY_TYPE PLUMBING
J 0
(-6025 5275);
DISPLAY 0.872340 (-6025 5275);
PAINT GREEN (-6025 5275);
DISPLAY INVISIBLE (-6025 5275);
FORCEPROP 1 LAST HDL_TAP TRUE
J 0
(-5700 5100);
DISPLAY 0.872340 (-5700 5100);
DISPLAY INVISIBLE (-5700 5100);
FORCEPROP 1 LAST PATH I122
J 0
(-6027 5225);
DISPLAY 0.872340 (-6027 5225);
PAINT GREEN (-6027 5225);
DISPLAY INVISIBLE (-6027 5225);
FORCEADD TAP..1
(-6025 5325);
FORCEPROP 3 LASTPIN (-6075 5325) SIG_NAME M_K_CPU0_SA_DQ<30>
J 0
(-6065 5335);
DISPLAY 0.659574 (-6065 5335);
PAINT MONO (-6065 5335);
DISPLAY INVISIBLE (-6065 5335);
FORCEPROP 1 LASTPIN (-6075 5325) BN 30
J 0
(-6087 5333);
DISPLAY 0.489362 (-6087 5333);
PAINT GREEN (-6087 5333);
FORCEPROP 2 LAST CDS_LIB mstr_standard
J 0
(-6025 5325);
DISPLAY 0.723404 (-6025 5325);
PAINT MONO (-6025 5325);
DISPLAY INVISIBLE (-6025 5325);
FORCEPROP 1 LAST BODY_TYPE PLUMBING
J 0
(-6025 5375);
DISPLAY 0.872340 (-6025 5375);
PAINT GREEN (-6025 5375);
DISPLAY INVISIBLE (-6025 5375);
FORCEPROP 1 LAST HDL_TAP TRUE
J 0
(-5700 5200);
DISPLAY 0.872340 (-5700 5200);
DISPLAY INVISIBLE (-5700 5200);
FORCEPROP 1 LAST PATH I123
J 0
(-6027 5325);
DISPLAY 0.872340 (-6027 5325);
PAINT GREEN (-6027 5325);
DISPLAY INVISIBLE (-6027 5325);
FORCEADD TAP..1
(-6025 5275);
FORCEPROP 3 LASTPIN (-6075 5275) SIG_NAME M_K_CPU0_SA_DQ<29>
J 0
(-6065 5285);
DISPLAY 0.659574 (-6065 5285);
PAINT MONO (-6065 5285);
DISPLAY INVISIBLE (-6065 5285);
FORCEPROP 1 LASTPIN (-6075 5275) BN 29
J 0
(-6087 5283);
DISPLAY 0.489362 (-6087 5283);
PAINT GREEN (-6087 5283);
FORCEPROP 2 LAST CDS_LIB mstr_standard
J 0
(-6025 5275);
DISPLAY 0.723404 (-6025 5275);
PAINT MONO (-6025 5275);
DISPLAY INVISIBLE (-6025 5275);
FORCEPROP 1 LAST BODY_TYPE PLUMBING
J 0
(-6025 5325);
DISPLAY 0.872340 (-6025 5325);
PAINT GREEN (-6025 5325);
DISPLAY INVISIBLE (-6025 5325);
FORCEPROP 1 LAST HDL_TAP TRUE
J 0
(-5700 5150);
DISPLAY 0.872340 (-5700 5150);
DISPLAY INVISIBLE (-5700 5150);
FORCEPROP 1 LAST PATH I124
J 0
(-6027 5275);
DISPLAY 0.872340 (-6027 5275);
PAINT GREEN (-6027 5275);
DISPLAY INVISIBLE (-6027 5275);
FORCEADD TAP..1
(-6025 5375);
FORCEPROP 3 LASTPIN (-6075 5375) SIG_NAME M_K_CPU0_SA_DQ<31>
J 0
(-6065 5385);
DISPLAY 0.659574 (-6065 5385);
PAINT MONO (-6065 5385);
DISPLAY INVISIBLE (-6065 5385);
FORCEPROP 1 LASTPIN (-6075 5375) BN 31
J 0
(-6087 5383);
DISPLAY 0.489362 (-6087 5383);
PAINT GREEN (-6087 5383);
FORCEPROP 2 LAST CDS_LIB mstr_standard
J 0
(-6025 5375);
DISPLAY 0.723404 (-6025 5375);
PAINT MONO (-6025 5375);
DISPLAY INVISIBLE (-6025 5375);
FORCEPROP 1 LAST BODY_TYPE PLUMBING
J 0
(-6025 5425);
DISPLAY 0.872340 (-6025 5425);
PAINT GREEN (-6025 5425);
DISPLAY INVISIBLE (-6025 5425);
FORCEPROP 1 LAST HDL_TAP TRUE
J 0
(-5700 5250);
DISPLAY 0.872340 (-5700 5250);
DISPLAY INVISIBLE (-5700 5250);
FORCEPROP 1 LAST PATH I125
J 0
(-6027 5375);
DISPLAY 0.872340 (-6027 5375);
PAINT GREEN (-6027 5375);
DISPLAY INVISIBLE (-6027 5375);
FORCEADD OFFPAGE..3
(-5350 5425);
FORCEPROP 2 LAST $XR0 20 
J 0
(-5136 5425);
DISPLAY 0.638298 (-5136 5425);
PAINT MONO (-5136 5425);
FORCEPROP 2 LAST CDS_LIB mstr_standard
J 0
(-5350 5425);
DISPLAY 0.723404 (-5350 5425);
PAINT MONO (-5350 5425);
DISPLAY INVISIBLE (-5350 5425);
FORCEPROP 1 LAST OFFPAGE TRUE
J 0
(-5025 5300);
DISPLAY 0.872340 (-5025 5300);
PAINT GREEN (-5025 5300);
DISPLAY INVISIBLE (-5025 5300);
FORCEPROP 1 LAST COMMENT_BODY TRUE
J 0
(-5400 5325);
DISPLAY 0.872340 (-5400 5325);
PAINT GREEN (-5400 5325);
DISPLAY INVISIBLE (-5400 5325);
FORCEPROP 2 LAST PATH I126
J 0
(-5150 5500);
DISPLAY 1.021277 (-5150 5500);
DISPLAY INVISIBLE (-5150 5500);
FORCEADD OFFPAGE..5
(-7200 1450);
FORCEPROP 2 LAST $XR0 96 
J 0
(-7424 1450);
DISPLAY 0.638298 (-7424 1450);
PAINT MONO (-7424 1450);
FORCEPROP 2 LAST BOM_COST MEM
J 0
(-7275 1525);
DISPLAY 0.808511 (-7275 1525);
DISPLAY INVISIBLE (-7275 1525);
FORCEPROP 2 LAST CDS_LIB mstr_standard
J 0
(-7200 1450);
DISPLAY 0.808511 (-7200 1450);
DISPLAY INVISIBLE (-7200 1450);
FORCEPROP 1 LAST OFFPAGE TRUE
J 0
(-6875 1325);
DISPLAY 0.872340 (-6875 1325);
PAINT GREEN (-6875 1325);
DISPLAY INVISIBLE (-6875 1325);
FORCEPROP 1 LAST COMMENT_BODY TRUE
J 0
(-7100 1375);
DISPLAY 0.872340 (-7100 1375);
PAINT GREEN (-7100 1375);
DISPLAY INVISIBLE (-7100 1375);
FORCEPROP 2 LAST PATH I127
J 0
(-7450 1500);
DISPLAY 1.021277 (-7450 1500);
DISPLAY INVISIBLE (-7450 1500);
FORCEADD GND..1
(-6425 1050);
FORCEPROP 3 LASTPIN (-6425 1100) SIG_NAME GND\g
J 0
(-6415 1110);
DISPLAY 0.659574 (-6415 1110);
PAINT MONO (-6415 1110);
DISPLAY INVISIBLE (-6415 1110);
FORCEPROP 2 LAST CDS_LIB mstr_symbols
J 0
(-6425 1050);
DISPLAY 0.808511 (-6425 1050);
DISPLAY INVISIBLE (-6425 1050);
FORCEPROP 2 LAST BOM_COST MEM
J 0
(-6525 1125);
DISPLAY 0.808511 (-6525 1125);
DISPLAY INVISIBLE (-6525 1125);
FORCEPROP 1 LAST SIZE 1B
J 0
(-6350 1000);
DISPLAY 0.851064 (-6350 1000);
PAINT GREEN (-6350 1000);
DISPLAY INVISIBLE (-6350 1000);
FORCEPROP 1 LAST VOLTAGE 0.0
J 0
(-6470 1007);
DISPLAY 0.723404 (-6470 1007);
PAINT SKYBLUE (-6470 1007);
DISPLAY INVISIBLE (-6470 1007);
FORCEPROP 1 LAST BODY_TYPE PLUMBING
J 0
(-6470 1007);
DISPLAY 0.340426 (-6470 1007);
PAINT GREEN (-6470 1007);
DISPLAY INVISIBLE (-6470 1007);
FORCEPROP 1 LAST HDL_POWER GND
J 0
(-6425 1200);
DISPLAY 0.851064 (-6425 1200);
PAINT GREEN (-6425 1200);
DISPLAY INVISIBLE (-6425 1200);
FORCEPROP 1 LAST PATH I128
J 0
(-6350 1050);
DISPLAY 0.872340 (-6350 1050);
PAINT AQUA (-6350 1050);
DISPLAY INVISIBLE (-6350 1050);
FORCEADD Q_RES..2
(-6425 1275);
FORCEPROP 1 LAST LOCATION R768
J 0
(-6380 1400);
DISPLAY 0.489362 (-6380 1400);
PAINT SKYBLUE (-6380 1400);
FORCEPROP 0 LAST $SEC 1
J 0
(-6375 1450);
DISPLAY 0.680851 (-6375 1450);
PAINT MONO (-6375 1450);
DISPLAY INVISIBLE (-6375 1450);
FORCEPROP 0 LAST CDS_SEC 1
J 0
(-6375 1450);
DISPLAY 1.021277 (-6375 1450);
DISPLAY INVISIBLE (-6375 1450);
FORCEPROP 1 LASTPIN (-6425 1375) $PN 1
J 0
(-6420 1337);
DISPLAY 0.489362 (-6420 1337);
PAINT MONO (-6420 1337);
FORCEPROP 1 LASTPIN (-6425 1175) $PN 2
J 0
(-6420 1185);
DISPLAY 0.489362 (-6420 1185);
PAINT MONO (-6420 1185);
FORCEPROP 1 LAST PACK_TYPE 0402LF
J 0
(-6385 1100);
DISPLAY 0.489362 (-6385 1100);
PAINT SKYBLUE (-6385 1100);
FORCEPROP 1 LAST VALUE 54.9K
J 0
(-6380 1350);
DISPLAY 0.489362 (-6380 1350);
PAINT SKYBLUE (-6380 1350);
FORCEPROP 1 LAST TOLERANCE 1%
J 0
(-6380 1300);
DISPLAY 0.489362 (-6380 1300);
PAINT SKYBLUE (-6380 1300);
FORCEPROP 1 LAST MATERIAL CHIP
J 0
(-6385 1200);
DISPLAY 0.489362 (-6385 1200);
PAINT SKYBLUE (-6385 1200);
FORCEPROP 1 LAST WATTAGE 1/16W
J 0
(-6385 1250);
DISPLAY 0.489362 (-6385 1250);
PAINT SKYBLUE (-6385 1250);
FORCEPROP 2 LAST CDS_LIB pure_quanta
J 0
(-6425 1275);
DISPLAY INVISIBLE (-6425 1275);
FORCEPROP 1 LAST PATH I129
J 0
(-6375 1450);
DISPLAY 0.978723 (-6375 1450);
PAINT WHITE (-6375 1450);
DISPLAY INVISIBLE (-6375 1450);
FORCEPROP 1 LAST PART_NUMBER CS35492FB03
J 0
(-6385 1150);
DISPLAY 0.489362 (-6385 1150);
PAINT SKYBLUE (-6385 1150);
DISPLAY INVISIBLE (-6385 1150);
FORCEADD OFFPAGE..6
(-8325 4025);
FORCEPROP 2 LAST $XR0 20 
J 0
(-8574 4025);
DISPLAY 0.638298 (-8574 4025);
PAINT MONO (-8574 4025);
FORCEPROP 2 LAST CDS_LIB mstr_standard
J 0
(-8325 4025);
DISPLAY 0.723404 (-8325 4025);
PAINT MONO (-8325 4025);
DISPLAY INVISIBLE (-8325 4025);
FORCEPROP 1 LAST OFFPAGE TRUE
J 0
(-8000 3900);
DISPLAY 0.872340 (-8000 3900);
PAINT GREEN (-8000 3900);
DISPLAY INVISIBLE (-8000 3900);
FORCEPROP 1 LAST COMMENT_BODY TRUE
J 0
(-8225 3950);
DISPLAY 0.872340 (-8225 3950);
PAINT GREEN (-8225 3950);
DISPLAY INVISIBLE (-8225 3950);
FORCEPROP 2 LAST PATH I13
J 0
(-8275 4100);
DISPLAY 1.021277 (-8275 4100);
DISPLAY INVISIBLE (-8275 4100);
FORCEADD GND..1
(-2125 1900);
FORCEPROP 3 LASTPIN (-2125 1950) SIG_NAME GND\g
J 0
(-2115 1960);
DISPLAY 0.659574 (-2115 1960);
PAINT MONO (-2115 1960);
DISPLAY INVISIBLE (-2115 1960);
FORCEPROP 1 LAST SIZE 1B
J 0
(-2050 1850);
DISPLAY 0.851064 (-2050 1850);
PAINT GREEN (-2050 1850);
DISPLAY INVISIBLE (-2050 1850);
FORCEPROP 2 LAST CDS_LIB mstr_symbols
J 0
(-2125 1900);
DISPLAY 0.723404 (-2125 1900);
DISPLAY INVISIBLE (-2125 1900);
FORCEPROP 1 LAST VOLTAGE 0.0
J 0
(-2170 1857);
DISPLAY 0.723404 (-2170 1857);
PAINT SKYBLUE (-2170 1857);
DISPLAY INVISIBLE (-2170 1857);
FORCEPROP 1 LAST BODY_TYPE PLUMBING
J 0
(-2170 1857);
DISPLAY 0.340426 (-2170 1857);
PAINT GREEN (-2170 1857);
DISPLAY INVISIBLE (-2170 1857);
FORCEPROP 1 LAST HDL_POWER GND
J 0
(-2125 2050);
DISPLAY 0.851064 (-2125 2050);
PAINT GREEN (-2125 2050);
DISPLAY INVISIBLE (-2125 2050);
FORCEPROP 1 LAST PATH I130
J 0
(-2050 1900);
DISPLAY 0.872340 (-2050 1900);
PAINT AQUA (-2050 1900);
DISPLAY INVISIBLE (-2050 1900);
FORCEADD OFFPAGE..1
(-8325 4375);
FORCEPROP 2 LAST $XR0 20 
J 0
(-8546 4375);
DISPLAY 0.638298 (-8546 4375);
PAINT MONO (-8546 4375);
FORCEPROP 2 LAST CDS_LIB mstr_standard
J 0
(-8325 4375);
DISPLAY 0.808511 (-8325 4375);
DISPLAY INVISIBLE (-8325 4375);
FORCEPROP 1 LAST OFFPAGE TRUE
J 0
(-8000 4250);
DISPLAY 0.872340 (-8000 4250);
PAINT GREEN (-8000 4250);
DISPLAY INVISIBLE (-8000 4250);
FORCEPROP 1 LAST COMMENT_BODY TRUE
J 0
(-8200 4275);
DISPLAY 0.872340 (-8200 4275);
PAINT GREEN (-8200 4275);
DISPLAY INVISIBLE (-8200 4275);
FORCEPROP 2 LAST PATH I14
J 0
(-8275 4450);
DISPLAY 1.021277 (-8275 4450);
DISPLAY INVISIBLE (-8275 4450);
FORCEADD GND..1
(-325 1675);
FORCEPROP 3 LASTPIN (-325 1725) SIG_NAME GND\g
J 0
(-315 1735);
DISPLAY 0.659574 (-315 1735);
PAINT MONO (-315 1735);
DISPLAY INVISIBLE (-315 1735);
FORCEPROP 1 LAST SIZE 1B
J 0
(-250 1625);
DISPLAY 0.851064 (-250 1625);
PAINT GREEN (-250 1625);
DISPLAY INVISIBLE (-250 1625);
FORCEPROP 2 LAST CDS_LIB mstr_symbols
J 0
(-325 1675);
DISPLAY 0.723404 (-325 1675);
DISPLAY INVISIBLE (-325 1675);
FORCEPROP 1 LAST VOLTAGE 0.0
J 0
(-370 1632);
DISPLAY 0.723404 (-370 1632);
PAINT SKYBLUE (-370 1632);
DISPLAY INVISIBLE (-370 1632);
FORCEPROP 1 LAST BODY_TYPE PLUMBING
J 0
(-370 1632);
DISPLAY 0.340426 (-370 1632);
PAINT GREEN (-370 1632);
DISPLAY INVISIBLE (-370 1632);
FORCEPROP 1 LAST HDL_POWER GND
J 0
(-325 1825);
DISPLAY 0.851064 (-325 1825);
PAINT GREEN (-325 1825);
DISPLAY INVISIBLE (-325 1825);
FORCEPROP 1 LAST PATH I144
J 0
(-250 1675);
DISPLAY 0.872340 (-250 1675);
PAINT AQUA (-250 1675);
DISPLAY INVISIBLE (-250 1675);
FORCEADD OFFPAGE..1
(-8325 4225);
FORCEPROP 2 LAST $XR0 20 
J 0
(-8546 4225);
DISPLAY 0.638298 (-8546 4225);
PAINT MONO (-8546 4225);
FORCEPROP 2 LAST CDS_LIB mstr_standard
J 0
(-8325 4225);
DISPLAY 0.808511 (-8325 4225);
DISPLAY INVISIBLE (-8325 4225);
FORCEPROP 1 LAST OFFPAGE TRUE
J 0
(-8000 4100);
DISPLAY 0.872340 (-8000 4100);
PAINT GREEN (-8000 4100);
DISPLAY INVISIBLE (-8000 4100);
FORCEPROP 1 LAST COMMENT_BODY TRUE
J 0
(-8200 4125);
DISPLAY 0.872340 (-8200 4125);
PAINT GREEN (-8200 4125);
DISPLAY INVISIBLE (-8200 4125);
FORCEPROP 2 LAST PATH I15
J 0
(-8275 4300);
DISPLAY 1.021277 (-8275 4300);
DISPLAY INVISIBLE (-8275 4300);
FORCEADD OFFPAGE..1
(-8325 4275);
FORCEPROP 2 LAST $XR0 20 
J 0
(-8546 4275);
DISPLAY 0.638298 (-8546 4275);
PAINT MONO (-8546 4275);
FORCEPROP 2 LAST CDS_LIB mstr_standard
J 0
(-8325 4275);
DISPLAY 0.723404 (-8325 4275);
PAINT MONO (-8325 4275);
DISPLAY INVISIBLE (-8325 4275);
FORCEPROP 1 LAST OFFPAGE TRUE
J 0
(-8000 4150);
DISPLAY 0.872340 (-8000 4150);
PAINT GREEN (-8000 4150);
DISPLAY INVISIBLE (-8000 4150);
FORCEPROP 1 LAST COMMENT_BODY TRUE
J 0
(-8200 4175);
DISPLAY 0.872340 (-8200 4175);
PAINT GREEN (-8200 4175);
DISPLAY INVISIBLE (-8200 4175);
FORCEPROP 2 LAST PATH I16
J 0
(-8275 4350);
DISPLAY 1.021277 (-8275 4350);
DISPLAY INVISIBLE (-8275 4350);
FORCEADD OFFPAGE..1
(-8325 4425);
FORCEPROP 2 LAST $XR0 20 
J 0
(-8546 4425);
DISPLAY 0.638298 (-8546 4425);
PAINT MONO (-8546 4425);
FORCEPROP 2 LAST CDS_LIB mstr_standard
J 0
(-8325 4425);
DISPLAY 0.723404 (-8325 4425);
PAINT MONO (-8325 4425);
DISPLAY INVISIBLE (-8325 4425);
FORCEPROP 1 LAST OFFPAGE TRUE
J 0
(-8000 4300);
DISPLAY 0.872340 (-8000 4300);
PAINT GREEN (-8000 4300);
DISPLAY INVISIBLE (-8000 4300);
FORCEPROP 1 LAST COMMENT_BODY TRUE
J 0
(-8200 4325);
DISPLAY 0.872340 (-8200 4325);
PAINT GREEN (-8200 4325);
DISPLAY INVISIBLE (-8200 4325);
FORCEPROP 2 LAST PATH I17
J 0
(-8275 4500);
DISPLAY 1.021277 (-8275 4500);
DISPLAY INVISIBLE (-8275 4500);
FORCEADD SCONN288_DDR506112002KQ..3
(-1225 3675);
FORCEPROP 1 LAST LOCATION J20
J 0
(-1675 5650);
DISPLAY 0.468085 (-1675 5650);
PAINT SKYBLUE (-1675 5650);
FORCEPROP 0 LAST $SEC 3
J 0
(-1675 5800);
DISPLAY 0.680851 (-1675 5800);
PAINT MONO (-1675 5800);
DISPLAY INVISIBLE (-1675 5800);
FORCEPROP 2 LAST CDS_SEC 3
J 0
(-1675 5800);
DISPLAY 1.021277 (-1675 5800);
DISPLAY INVISIBLE (-1675 5800);
FORCEPROP 0 LASTPIN (-625 2075) $PN G1
J 0
(-615 2085);
DISPLAY 0.680851 (-615 2085);
PAINT MONO (-615 2085);
FORCEPROP 0 LASTPIN (-625 2025) $PN G2
J 0
(-615 2035);
DISPLAY 0.680851 (-615 2035);
PAINT MONO (-615 2035);
FORCEPROP 0 LASTPIN (-625 1975) $PN G3
J 0
(-615 1985);
DISPLAY 0.680851 (-615 1985);
PAINT MONO (-615 1985);
FORCEPROP 0 LASTPIN (-1825 5225) $PN 1
J 2
(-1835 5235);
DISPLAY 0.680851 (-1835 5235);
PAINT MONO (-1835 5235);
FORCEPROP 0 LASTPIN (-1825 5275) $PN 145
J 2
(-1835 5285);
DISPLAY 0.680851 (-1835 5285);
PAINT MONO (-1835 5285);
FORCEPROP 0 LASTPIN (-1825 5325) $PN 146
J 2
(-1835 5335);
DISPLAY 0.680851 (-1835 5335);
PAINT MONO (-1835 5335);
FORCEPROP 0 LASTPIN (-625 2175) $PN 6
J 0
(-615 2185);
DISPLAY 0.680851 (-615 2185);
PAINT MONO (-615 2185);
FORCEPROP 0 LASTPIN (-625 2225) $PN 8
J 0
(-615 2235);
DISPLAY 0.680851 (-615 2235);
PAINT MONO (-615 2235);
FORCEPROP 0 LASTPIN (-625 2275) $PN 10
J 0
(-615 2285);
DISPLAY 0.680851 (-615 2285);
PAINT MONO (-615 2285);
FORCEPROP 0 LASTPIN (-625 2325) $PN 13
J 0
(-615 2335);
DISPLAY 0.680851 (-615 2335);
PAINT MONO (-615 2335);
FORCEPROP 0 LASTPIN (-625 2375) $PN 15
J 0
(-615 2385);
DISPLAY 0.680851 (-615 2385);
PAINT MONO (-615 2385);
FORCEPROP 0 LASTPIN (-625 2425) $PN 17
J 0
(-615 2435);
DISPLAY 0.680851 (-615 2435);
PAINT MONO (-615 2435);
FORCEPROP 0 LASTPIN (-625 2475) $PN 19
J 0
(-615 2485);
DISPLAY 0.680851 (-615 2485);
PAINT MONO (-615 2485);
FORCEPROP 0 LASTPIN (-625 2525) $PN 21
J 0
(-615 2535);
DISPLAY 0.680851 (-615 2535);
PAINT MONO (-615 2535);
FORCEPROP 0 LASTPIN (-625 2575) $PN 24
J 0
(-615 2585);
DISPLAY 0.680851 (-615 2585);
PAINT MONO (-615 2585);
FORCEPROP 0 LASTPIN (-625 2625) $PN 26
J 0
(-615 2635);
DISPLAY 0.680851 (-615 2635);
PAINT MONO (-615 2635);
FORCEPROP 0 LASTPIN (-625 2675) $PN 28
J 0
(-615 2685);
DISPLAY 0.680851 (-615 2685);
PAINT MONO (-615 2685);
FORCEPROP 0 LASTPIN (-625 2725) $PN 30
J 0
(-615 2735);
DISPLAY 0.680851 (-615 2735);
PAINT MONO (-615 2735);
FORCEPROP 0 LASTPIN (-625 2775) $PN 32
J 0
(-615 2785);
DISPLAY 0.680851 (-615 2785);
PAINT MONO (-615 2785);
FORCEPROP 0 LASTPIN (-625 2825) $PN 35
J 0
(-615 2835);
DISPLAY 0.680851 (-615 2835);
PAINT MONO (-615 2835);
FORCEPROP 0 LASTPIN (-625 2875) $PN 37
J 0
(-615 2885);
DISPLAY 0.680851 (-615 2885);
PAINT MONO (-615 2885);
FORCEPROP 0 LASTPIN (-625 2925) $PN 39
J 0
(-615 2935);
DISPLAY 0.680851 (-615 2935);
PAINT MONO (-615 2935);
FORCEPROP 0 LASTPIN (-625 2975) $PN 41
J 0
(-615 2985);
DISPLAY 0.680851 (-615 2985);
PAINT MONO (-615 2985);
FORCEPROP 0 LASTPIN (-625 3025) $PN 43
J 0
(-615 3035);
DISPLAY 0.680851 (-615 3035);
PAINT MONO (-615 3035);
FORCEPROP 0 LASTPIN (-625 3075) $PN 46
J 0
(-615 3085);
DISPLAY 0.680851 (-615 3085);
PAINT MONO (-615 3085);
FORCEPROP 0 LASTPIN (-625 3125) $PN 48
J 0
(-615 3135);
DISPLAY 0.680851 (-615 3135);
PAINT MONO (-615 3135);
FORCEPROP 0 LASTPIN (-625 3175) $PN 50
J 0
(-615 3185);
DISPLAY 0.680851 (-615 3185);
PAINT MONO (-615 3185);
FORCEPROP 0 LASTPIN (-625 3225) $PN 52
J 0
(-615 3235);
DISPLAY 0.680851 (-615 3235);
PAINT MONO (-615 3235);
FORCEPROP 0 LASTPIN (-625 3275) $PN 54
J 0
(-615 3285);
DISPLAY 0.680851 (-615 3285);
PAINT MONO (-615 3285);
FORCEPROP 0 LASTPIN (-625 3325) $PN 57
J 0
(-615 3335);
DISPLAY 0.680851 (-615 3335);
PAINT MONO (-615 3335);
FORCEPROP 0 LASTPIN (-625 3375) $PN 59
J 0
(-615 3385);
DISPLAY 0.680851 (-615 3385);
PAINT MONO (-615 3385);
FORCEPROP 0 LASTPIN (-625 3425) $PN 61
J 0
(-615 3435);
DISPLAY 0.680851 (-615 3435);
PAINT MONO (-615 3435);
FORCEPROP 0 LASTPIN (-625 3475) $PN 63
J 0
(-615 3485);
DISPLAY 0.680851 (-615 3485);
PAINT MONO (-615 3485);
FORCEPROP 0 LASTPIN (-625 3525) $PN 65
J 0
(-615 3535);
DISPLAY 0.680851 (-615 3535);
PAINT MONO (-615 3535);
FORCEPROP 0 LASTPIN (-625 3575) $PN 67
J 0
(-615 3585);
DISPLAY 0.680851 (-615 3585);
PAINT MONO (-615 3585);
FORCEPROP 0 LASTPIN (-625 3625) $PN 69
J 0
(-615 3635);
DISPLAY 0.680851 (-615 3635);
PAINT MONO (-615 3635);
FORCEPROP 0 LASTPIN (-625 3675) $PN 71
J 0
(-615 3685);
DISPLAY 0.680851 (-615 3685);
PAINT MONO (-615 3685);
FORCEPROP 0 LASTPIN (-625 3725) $PN 73
J 0
(-615 3735);
DISPLAY 0.680851 (-615 3735);
PAINT MONO (-615 3735);
FORCEPROP 0 LASTPIN (-625 3775) $PN 75
J 0
(-615 3785);
DISPLAY 0.680851 (-615 3785);
PAINT MONO (-615 3785);
FORCEPROP 0 LASTPIN (-625 3825) $PN 77
J 0
(-615 3835);
DISPLAY 0.680851 (-615 3835);
PAINT MONO (-615 3835);
FORCEPROP 0 LASTPIN (-625 3875) $PN 79
J 0
(-615 3885);
DISPLAY 0.680851 (-615 3885);
PAINT MONO (-615 3885);
FORCEPROP 0 LASTPIN (-625 3925) $PN 81
J 0
(-615 3935);
DISPLAY 0.680851 (-615 3935);
PAINT MONO (-615 3935);
FORCEPROP 0 LASTPIN (-625 3975) $PN 83
J 0
(-615 3985);
DISPLAY 0.680851 (-615 3985);
PAINT MONO (-615 3985);
FORCEPROP 0 LASTPIN (-625 4025) $PN 85
J 0
(-615 4035);
DISPLAY 0.680851 (-615 4035);
PAINT MONO (-615 4035);
FORCEPROP 0 LASTPIN (-625 4075) $PN 88
J 0
(-615 4085);
DISPLAY 0.680851 (-615 4085);
PAINT MONO (-615 4085);
FORCEPROP 0 LASTPIN (-625 4125) $PN 90
J 0
(-615 4135);
DISPLAY 0.680851 (-615 4135);
PAINT MONO (-615 4135);
FORCEPROP 0 LASTPIN (-625 4175) $PN 92
J 0
(-615 4185);
DISPLAY 0.680851 (-615 4185);
PAINT MONO (-615 4185);
FORCEPROP 0 LASTPIN (-625 4225) $PN 95
J 0
(-615 4235);
DISPLAY 0.680851 (-615 4235);
PAINT MONO (-615 4235);
FORCEPROP 0 LASTPIN (-625 4275) $PN 97
J 0
(-615 4285);
DISPLAY 0.680851 (-615 4285);
PAINT MONO (-615 4285);
FORCEPROP 0 LASTPIN (-625 4325) $PN 99
J 0
(-615 4335);
DISPLAY 0.680851 (-615 4335);
PAINT MONO (-615 4335);
FORCEPROP 0 LASTPIN (-625 4375) $PN 101
J 0
(-615 4385);
DISPLAY 0.680851 (-615 4385);
PAINT MONO (-615 4385);
FORCEPROP 0 LASTPIN (-625 4425) $PN 103
J 0
(-615 4435);
DISPLAY 0.680851 (-615 4435);
PAINT MONO (-615 4435);
FORCEPROP 0 LASTPIN (-625 4475) $PN 106
J 0
(-615 4485);
DISPLAY 0.680851 (-615 4485);
PAINT MONO (-615 4485);
FORCEPROP 0 LASTPIN (-625 4525) $PN 108
J 0
(-615 4535);
DISPLAY 0.680851 (-615 4535);
PAINT MONO (-615 4535);
FORCEPROP 0 LASTPIN (-625 4575) $PN 110
J 0
(-615 4585);
DISPLAY 0.680851 (-615 4585);
PAINT MONO (-615 4585);
FORCEPROP 0 LASTPIN (-625 4625) $PN 112
J 0
(-615 4635);
DISPLAY 0.680851 (-615 4635);
PAINT MONO (-615 4635);
FORCEPROP 0 LASTPIN (-625 4675) $PN 114
J 0
(-615 4685);
DISPLAY 0.680851 (-615 4685);
PAINT MONO (-615 4685);
FORCEPROP 0 LASTPIN (-625 4725) $PN 117
J 0
(-615 4735);
DISPLAY 0.680851 (-615 4735);
PAINT MONO (-615 4735);
FORCEPROP 0 LASTPIN (-625 4775) $PN 119
J 0
(-615 4785);
DISPLAY 0.680851 (-615 4785);
PAINT MONO (-615 4785);
FORCEPROP 0 LASTPIN (-625 4825) $PN 121
J 0
(-615 4835);
DISPLAY 0.680851 (-615 4835);
PAINT MONO (-615 4835);
FORCEPROP 0 LASTPIN (-625 4875) $PN 123
J 0
(-615 4885);
DISPLAY 0.680851 (-615 4885);
PAINT MONO (-615 4885);
FORCEPROP 0 LASTPIN (-625 4925) $PN 125
J 0
(-615 4935);
DISPLAY 0.680851 (-615 4935);
PAINT MONO (-615 4935);
FORCEPROP 0 LASTPIN (-625 4975) $PN 128
J 0
(-615 4985);
DISPLAY 0.680851 (-615 4985);
PAINT MONO (-615 4985);
FORCEPROP 0 LASTPIN (-625 5025) $PN 130
J 0
(-615 5035);
DISPLAY 0.680851 (-615 5035);
PAINT MONO (-615 5035);
FORCEPROP 0 LASTPIN (-625 5075) $PN 132
J 0
(-615 5085);
DISPLAY 0.680851 (-615 5085);
PAINT MONO (-615 5085);
FORCEPROP 0 LASTPIN (-625 5125) $PN 134
J 0
(-615 5135);
DISPLAY 0.680851 (-615 5135);
PAINT MONO (-615 5135);
FORCEPROP 0 LASTPIN (-625 5175) $PN 136
J 0
(-615 5185);
DISPLAY 0.680851 (-615 5185);
PAINT MONO (-615 5185);
FORCEPROP 0 LASTPIN (-625 5225) $PN 139
J 0
(-615 5235);
DISPLAY 0.680851 (-615 5235);
PAINT MONO (-615 5235);
FORCEPROP 0 LASTPIN (-625 5275) $PN 141
J 0
(-615 5285);
DISPLAY 0.680851 (-615 5285);
PAINT MONO (-615 5285);
FORCEPROP 0 LASTPIN (-625 5325) $PN 143
J 0
(-615 5335);
DISPLAY 0.680851 (-615 5335);
PAINT MONO (-615 5335);
FORCEPROP 0 LASTPIN (-1825 2075) $PN 151
J 2
(-1835 2085);
DISPLAY 0.680851 (-1835 2085);
PAINT MONO (-1835 2085);
FORCEPROP 0 LASTPIN (-1825 2125) $PN 153
J 2
(-1835 2135);
DISPLAY 0.680851 (-1835 2135);
PAINT MONO (-1835 2135);
FORCEPROP 0 LASTPIN (-1825 2175) $PN 155
J 2
(-1835 2185);
DISPLAY 0.680851 (-1835 2185);
PAINT MONO (-1835 2185);
FORCEPROP 0 LASTPIN (-1825 2225) $PN 158
J 2
(-1835 2235);
DISPLAY 0.680851 (-1835 2235);
PAINT MONO (-1835 2235);
FORCEPROP 0 LASTPIN (-1825 2275) $PN 160
J 2
(-1835 2285);
DISPLAY 0.680851 (-1835 2285);
PAINT MONO (-1835 2285);
FORCEPROP 0 LASTPIN (-1825 2325) $PN 162
J 2
(-1835 2335);
DISPLAY 0.680851 (-1835 2335);
PAINT MONO (-1835 2335);
FORCEPROP 0 LASTPIN (-1825 2375) $PN 164
J 2
(-1835 2385);
DISPLAY 0.680851 (-1835 2385);
PAINT MONO (-1835 2385);
FORCEPROP 0 LASTPIN (-1825 2425) $PN 166
J 2
(-1835 2435);
DISPLAY 0.680851 (-1835 2435);
PAINT MONO (-1835 2435);
FORCEPROP 0 LASTPIN (-1825 2475) $PN 169
J 2
(-1835 2485);
DISPLAY 0.680851 (-1835 2485);
PAINT MONO (-1835 2485);
FORCEPROP 0 LASTPIN (-1825 2525) $PN 171
J 2
(-1835 2535);
DISPLAY 0.680851 (-1835 2535);
PAINT MONO (-1835 2535);
FORCEPROP 0 LASTPIN (-1825 2575) $PN 173
J 2
(-1835 2585);
DISPLAY 0.680851 (-1835 2585);
PAINT MONO (-1835 2585);
FORCEPROP 0 LASTPIN (-1825 2625) $PN 175
J 2
(-1835 2635);
DISPLAY 0.680851 (-1835 2635);
PAINT MONO (-1835 2635);
FORCEPROP 0 LASTPIN (-1825 2675) $PN 177
J 2
(-1835 2685);
DISPLAY 0.680851 (-1835 2685);
PAINT MONO (-1835 2685);
FORCEPROP 0 LASTPIN (-1825 2725) $PN 180
J 2
(-1835 2735);
DISPLAY 0.680851 (-1835 2735);
PAINT MONO (-1835 2735);
FORCEPROP 0 LASTPIN (-1825 2775) $PN 182
J 2
(-1835 2785);
DISPLAY 0.680851 (-1835 2785);
PAINT MONO (-1835 2785);
FORCEPROP 0 LASTPIN (-1825 2825) $PN 184
J 2
(-1835 2835);
DISPLAY 0.680851 (-1835 2835);
PAINT MONO (-1835 2835);
FORCEPROP 0 LASTPIN (-1825 2875) $PN 186
J 2
(-1835 2885);
DISPLAY 0.680851 (-1835 2885);
PAINT MONO (-1835 2885);
FORCEPROP 0 LASTPIN (-1825 2925) $PN 188
J 2
(-1835 2935);
DISPLAY 0.680851 (-1835 2935);
PAINT MONO (-1835 2935);
FORCEPROP 0 LASTPIN (-1825 2975) $PN 191
J 2
(-1835 2985);
DISPLAY 0.680851 (-1835 2985);
PAINT MONO (-1835 2985);
FORCEPROP 0 LASTPIN (-1825 3025) $PN 193
J 2
(-1835 3035);
DISPLAY 0.680851 (-1835 3035);
PAINT MONO (-1835 3035);
FORCEPROP 0 LASTPIN (-1825 3075) $PN 195
J 2
(-1835 3085);
DISPLAY 0.680851 (-1835 3085);
PAINT MONO (-1835 3085);
FORCEPROP 0 LASTPIN (-1825 3125) $PN 197
J 2
(-1835 3135);
DISPLAY 0.680851 (-1835 3135);
PAINT MONO (-1835 3135);
FORCEPROP 0 LASTPIN (-1825 3175) $PN 199
J 2
(-1835 3185);
DISPLAY 0.680851 (-1835 3185);
PAINT MONO (-1835 3185);
FORCEPROP 0 LASTPIN (-1825 3225) $PN 202
J 2
(-1835 3235);
DISPLAY 0.680851 (-1835 3235);
PAINT MONO (-1835 3235);
FORCEPROP 0 LASTPIN (-1825 3275) $PN 204
J 2
(-1835 3285);
DISPLAY 0.680851 (-1835 3285);
PAINT MONO (-1835 3285);
FORCEPROP 0 LASTPIN (-1825 3325) $PN 206
J 2
(-1835 3335);
DISPLAY 0.680851 (-1835 3335);
PAINT MONO (-1835 3335);
FORCEPROP 0 LASTPIN (-1825 3375) $PN 208
J 2
(-1835 3385);
DISPLAY 0.680851 (-1835 3385);
PAINT MONO (-1835 3385);
FORCEPROP 0 LASTPIN (-1825 3425) $PN 210
J 2
(-1835 3435);
DISPLAY 0.680851 (-1835 3435);
PAINT MONO (-1835 3435);
FORCEPROP 0 LASTPIN (-1825 3475) $PN 212
J 2
(-1835 3485);
DISPLAY 0.680851 (-1835 3485);
PAINT MONO (-1835 3485);
FORCEPROP 0 LASTPIN (-1825 3525) $PN 214
J 2
(-1835 3535);
DISPLAY 0.680851 (-1835 3535);
PAINT MONO (-1835 3535);
FORCEPROP 0 LASTPIN (-1825 3575) $PN 216
J 2
(-1835 3585);
DISPLAY 0.680851 (-1835 3585);
PAINT MONO (-1835 3585);
FORCEPROP 0 LASTPIN (-1825 3625) $PN 219
J 2
(-1835 3635);
DISPLAY 0.680851 (-1835 3635);
PAINT MONO (-1835 3635);
FORCEPROP 0 LASTPIN (-1825 3675) $PN 222
J 2
(-1835 3685);
DISPLAY 0.680851 (-1835 3685);
PAINT MONO (-1835 3685);
FORCEPROP 0 LASTPIN (-1825 3725) $PN 224
J 2
(-1835 3735);
DISPLAY 0.680851 (-1835 3735);
PAINT MONO (-1835 3735);
FORCEPROP 0 LASTPIN (-1825 3775) $PN 226
J 2
(-1835 3785);
DISPLAY 0.680851 (-1835 3785);
PAINT MONO (-1835 3785);
FORCEPROP 0 LASTPIN (-1825 3825) $PN 228
J 2
(-1835 3835);
DISPLAY 0.680851 (-1835 3835);
PAINT MONO (-1835 3835);
FORCEPROP 0 LASTPIN (-1825 3875) $PN 230
J 2
(-1835 3885);
DISPLAY 0.680851 (-1835 3885);
PAINT MONO (-1835 3885);
FORCEPROP 0 LASTPIN (-1825 3925) $PN 233
J 2
(-1835 3935);
DISPLAY 0.680851 (-1835 3935);
PAINT MONO (-1835 3935);
FORCEPROP 0 LASTPIN (-1825 3975) $PN 235
J 2
(-1835 3985);
DISPLAY 0.680851 (-1835 3985);
PAINT MONO (-1835 3985);
FORCEPROP 0 LASTPIN (-1825 4025) $PN 237
J 2
(-1835 4035);
DISPLAY 0.680851 (-1835 4035);
PAINT MONO (-1835 4035);
FORCEPROP 0 LASTPIN (-1825 4075) $PN 240
J 2
(-1835 4085);
DISPLAY 0.680851 (-1835 4085);
PAINT MONO (-1835 4085);
FORCEPROP 0 LASTPIN (-1825 4125) $PN 242
J 2
(-1835 4135);
DISPLAY 0.680851 (-1835 4135);
PAINT MONO (-1835 4135);
FORCEPROP 0 LASTPIN (-1825 4175) $PN 244
J 2
(-1835 4185);
DISPLAY 0.680851 (-1835 4185);
PAINT MONO (-1835 4185);
FORCEPROP 0 LASTPIN (-1825 4225) $PN 246
J 2
(-1835 4235);
DISPLAY 0.680851 (-1835 4235);
PAINT MONO (-1835 4235);
FORCEPROP 0 LASTPIN (-1825 4275) $PN 248
J 2
(-1835 4285);
DISPLAY 0.680851 (-1835 4285);
PAINT MONO (-1835 4285);
FORCEPROP 0 LASTPIN (-1825 4325) $PN 251
J 2
(-1835 4335);
DISPLAY 0.680851 (-1835 4335);
PAINT MONO (-1835 4335);
FORCEPROP 0 LASTPIN (-1825 4375) $PN 253
J 2
(-1835 4385);
DISPLAY 0.680851 (-1835 4385);
PAINT MONO (-1835 4385);
FORCEPROP 0 LASTPIN (-1825 4425) $PN 255
J 2
(-1835 4435);
DISPLAY 0.680851 (-1835 4435);
PAINT MONO (-1835 4435);
FORCEPROP 0 LASTPIN (-1825 4475) $PN 257
J 2
(-1835 4485);
DISPLAY 0.680851 (-1835 4485);
PAINT MONO (-1835 4485);
FORCEPROP 0 LASTPIN (-1825 4525) $PN 259
J 2
(-1835 4535);
DISPLAY 0.680851 (-1835 4535);
PAINT MONO (-1835 4535);
FORCEPROP 0 LASTPIN (-1825 4575) $PN 262
J 2
(-1835 4585);
DISPLAY 0.680851 (-1835 4585);
PAINT MONO (-1835 4585);
FORCEPROP 0 LASTPIN (-1825 4625) $PN 264
J 2
(-1835 4635);
DISPLAY 0.680851 (-1835 4635);
PAINT MONO (-1835 4635);
FORCEPROP 0 LASTPIN (-1825 4675) $PN 266
J 2
(-1835 4685);
DISPLAY 0.680851 (-1835 4685);
PAINT MONO (-1835 4685);
FORCEPROP 0 LASTPIN (-1825 4725) $PN 268
J 2
(-1835 4735);
DISPLAY 0.680851 (-1835 4735);
PAINT MONO (-1835 4735);
FORCEPROP 0 LASTPIN (-1825 4775) $PN 270
J 2
(-1835 4785);
DISPLAY 0.680851 (-1835 4785);
PAINT MONO (-1835 4785);
FORCEPROP 0 LASTPIN (-1825 4825) $PN 273
J 2
(-1835 4835);
DISPLAY 0.680851 (-1835 4835);
PAINT MONO (-1835 4835);
FORCEPROP 0 LASTPIN (-1825 4875) $PN 275
J 2
(-1835 4885);
DISPLAY 0.680851 (-1835 4885);
PAINT MONO (-1835 4885);
FORCEPROP 0 LASTPIN (-1825 4925) $PN 277
J 2
(-1835 4935);
DISPLAY 0.680851 (-1835 4935);
PAINT MONO (-1835 4935);
FORCEPROP 0 LASTPIN (-1825 4975) $PN 279
J 2
(-1835 4985);
DISPLAY 0.680851 (-1835 4985);
PAINT MONO (-1835 4985);
FORCEPROP 0 LASTPIN (-1825 5025) $PN 281
J 2
(-1835 5035);
DISPLAY 0.680851 (-1835 5035);
PAINT MONO (-1835 5035);
FORCEPROP 0 LASTPIN (-1825 5075) $PN 284
J 2
(-1835 5085);
DISPLAY 0.680851 (-1835 5085);
PAINT MONO (-1835 5085);
FORCEPROP 0 LASTPIN (-1825 5125) $PN 286
J 2
(-1835 5135);
DISPLAY 0.680851 (-1835 5135);
PAINT MONO (-1835 5135);
FORCEPROP 0 LASTPIN (-1825 5175) $PN 288
J 2
(-1835 5185);
DISPLAY 0.680851 (-1835 5185);
PAINT MONO (-1835 5185);
FORCEPROP 2 LAST PART_TYPE SMLF
J 0
(-1675 5750);
DISPLAY 1.021277 (-1675 5750);
FORCEPROP 2 LAST VALUE SCONN288_DDR506112002KQ
J 0
(-1675 5700);
DISPLAY 0.489362 (-1675 5700);
PAINT SKYBLUE (-1675 5700);
FORCEPROP 1 LAST MATERIAL IO
J 0
(-1675 5500);
DISPLAY 0.468085 (-1675 5500);
PAINT SKYBLUE (-1675 5500);
FORCEPROP 1 LAST CDS_LMAN_SYM_OUTLINE -450,1800,450,-1750
J 0
(-1225 3675);
DISPLAY 0.468085 (-1225 3675);
PAINT GREEN (-1225 3675);
DISPLAY INVISIBLE (-1225 3675);
FORCEPROP 1 LAST NEEDS_NO_SIZE TRUE
J 0
(-1225 3675);
DISPLAY 0.723404 (-1225 3675);
PAINT GREEN (-1225 3675);
DISPLAY INVISIBLE (-1225 3675);
FORCEPROP 2 LAST CDS_LIB pure_quanta
J 0
(-1225 3675);
DISPLAY INVISIBLE (-1225 3675);
FORCEPROP 1 LAST PATH I177
J 0
(-1225 3675);
DISPLAY 0.723404 (-1225 3675);
PAINT GREEN (-1225 3675);
DISPLAY INVISIBLE (-1225 3675);
FORCEPROP 1 LAST PART_NUMBER DFHST8FS479
J 0
(-1675 5575);
DISPLAY 0.468085 (-1675 5575);
PAINT SKYBLUE (-1675 5575);
DISPLAY INVISIBLE (-1675 5575);
FORCEADD OFFPAGE..1
(-8325 4575);
FORCEPROP 2 LAST $XR0 20 
J 0
(-8546 4575);
DISPLAY 0.638298 (-8546 4575);
PAINT MONO (-8546 4575);
FORCEPROP 2 LAST CDS_LIB mstr_standard
J 0
(-8325 4575);
DISPLAY 0.723404 (-8325 4575);
PAINT MONO (-8325 4575);
DISPLAY INVISIBLE (-8325 4575);
FORCEPROP 1 LAST OFFPAGE TRUE
J 0
(-8000 4450);
DISPLAY 0.872340 (-8000 4450);
PAINT GREEN (-8000 4450);
DISPLAY INVISIBLE (-8000 4450);
FORCEPROP 1 LAST COMMENT_BODY TRUE
J 0
(-8200 4475);
DISPLAY 0.872340 (-8200 4475);
PAINT GREEN (-8200 4475);
DISPLAY INVISIBLE (-8200 4475);
FORCEPROP 2 LAST PATH I18
J 0
(-8275 4650);
DISPLAY 1.021277 (-8275 4650);
DISPLAY INVISIBLE (-8275 4650);
FORCEADD Q_CAP..1
R 2
(-8600 3200);
FORCEPROP 1 LAST LOCATION C128
J 2
(-8650 3300);
DISPLAY 0.489362 (-8650 3300);
PAINT SKYBLUE (-8650 3300);
FORCEPROP 0 LAST $SEC 1
J 0
(-8650 3350);
DISPLAY 0.680851 (-8650 3350);
PAINT MONO (-8650 3350);
DISPLAY INVISIBLE (-8650 3350);
FORCEPROP 0 LAST CDS_SEC 1
J 0
(-8650 3350);
DISPLAY 1.021277 (-8650 3350);
DISPLAY INVISIBLE (-8650 3350);
FORCEPROP 1 LASTPIN (-8600 3300) $PN 1
J 2
(-8610 3280);
DISPLAY 0.489362 (-8610 3280);
PAINT MONO (-8610 3280);
FORCEPROP 1 LASTPIN (-8600 3100) $PN 2
J 2
(-8610 3080);
DISPLAY 0.489362 (-8610 3080);
PAINT MONO (-8610 3080);
FORCEPROP 1 LAST VALUE 0.1UF
J 2
(-8650 3250);
DISPLAY 0.489362 (-8650 3250);
PAINT SKYBLUE (-8650 3250);
FORCEPROP 1 LAST VOLTAGE 25V
J 2
(-8650 3200);
DISPLAY 0.489362 (-8650 3200);
PAINT SKYBLUE (-8650 3200);
FORCEPROP 1 LAST PACK_TYPE 0402
J 2
(-8650 3000);
DISPLAY 0.489362 (-8650 3000);
PAINT SKYBLUE (-8650 3000);
FORCEPROP 1 LAST TOLERANCE 10%
J 2
(-8650 3150);
DISPLAY 0.489362 (-8650 3150);
PAINT SKYBLUE (-8650 3150);
FORCEPROP 1 LAST MATERIAL X7R
J 2
(-8650 3100);
DISPLAY 0.489362 (-8650 3100);
PAINT SKYBLUE (-8650 3100);
FORCEPROP 2 LAST CDS_LIB pure_quanta
J 0
(-8600 3200);
DISPLAY INVISIBLE (-8600 3200);
FORCEPROP 0 LAST BOM_COST MEM
J 2
(-8655 3345);
DISPLAY 0.595745 (-8655 3345);
PAINT MONO (-8655 3345);
DISPLAY INVISIBLE (-8655 3345);
FORCEPROP 2 LAST ROOM 
J 2
(-8655 3345);
DISPLAY 0.595745 (-8655 3345);
PAINT RED (-8655 3345);
DISPLAY INVISIBLE (-8655 3345);
FORCEPROP 1 LAST PATH I185
J 2
(-8650 3350);
DISPLAY 0.978723 (-8650 3350);
PAINT WHITE (-8650 3350);
DISPLAY INVISIBLE (-8650 3350);
FORCEPROP 1 LAST PART_NUMBER CH4104K1B00
J 2
(-8650 3050);
DISPLAY 0.489362 (-8650 3050);
PAINT SKYBLUE (-8650 3050);
DISPLAY INVISIBLE (-8650 3050);
FORCEADD GND..1
(-8600 2975);
FORCEPROP 3 LASTPIN (-8600 3025) SIG_NAME GND\g
J 0
(-8590 3035);
DISPLAY 0.659574 (-8590 3035);
PAINT MONO (-8590 3035);
DISPLAY INVISIBLE (-8590 3035);
FORCEPROP 2 LAST BOM_COST MEM
J 0
(-8575 3100);
DISPLAY 0.659574 (-8575 3100);
DISPLAY INVISIBLE (-8575 3100);
FORCEPROP 1 LAST SIZE 1B
J 0
(-8525 2925);
DISPLAY 0.723404 (-8525 2925);
PAINT GREEN (-8525 2925);
DISPLAY INVISIBLE (-8525 2925);
FORCEPROP 2 LAST CDS_LIB mstr_symbols
J 0
(-8600 2975);
DISPLAY 0.808511 (-8600 2975);
DISPLAY INVISIBLE (-8600 2975);
FORCEPROP 1 LAST VOLTAGE 0
J 0
(-8620 3070);
DISPLAY 0.829787 (-8620 3070);
PAINT SKYBLUE (-8620 3070);
DISPLAY INVISIBLE (-8620 3070);
FORCEPROP 2 LAST ROOM MEM_EFGH_DECOUPLING_CAPS
J 0
(-8575 3050);
DISPLAY 0.659574 (-8575 3050);
PAINT RED (-8575 3050);
DISPLAY INVISIBLE (-8575 3050);
FORCEPROP 1 LAST BODY_TYPE PLUMBING
J 0
(-8645 2932);
DISPLAY 0.276596 (-8645 2932);
PAINT GREEN (-8645 2932);
DISPLAY INVISIBLE (-8645 2932);
FORCEPROP 1 LAST HDL_POWER GND
J 0
(-8600 3125);
DISPLAY 0.723404 (-8600 3125);
PAINT GREEN (-8600 3125);
DISPLAY INVISIBLE (-8600 3125);
FORCEPROP 1 LAST PATH I186
J 0
(-8525 2975);
DISPLAY 0.872340 (-8525 2975);
PAINT AQUA (-8525 2975);
DISPLAY INVISIBLE (-8525 2975);
FORCEADD OFFPAGE..6
(-9025 2125);
FORCEPROP 2 LAST $XR4 97 
J 0
(-9274 2197);
DISPLAY 0.638298 (-9274 2197);
PAINT MONO (-9274 2197);
FORCEPROP 2 LAST $XR3 95 
J 0
(-9274 2053);
DISPLAY 0.638298 (-9274 2053);
PAINT MONO (-9274 2053);
FORCEPROP 2 LAST $XR2 94 
J 0
(-9274 2161);
DISPLAY 0.638298 (-9274 2161);
PAINT MONO (-9274 2161);
FORCEPROP 2 LAST $XR1 93 
J 0
(-9274 2089);
DISPLAY 0.638298 (-9274 2089);
PAINT MONO (-9274 2089);
FORCEPROP 2 LAST $XR0 92 
J 0
(-9274 2125);
DISPLAY 0.638298 (-9274 2125);
PAINT MONO (-9274 2125);
FORCEPROP 2 LAST CDS_LIB mstr_standard
J 0
(-9025 2125);
DISPLAY INVISIBLE (-9025 2125);
FORCEPROP 1 LAST OFFPAGE TRUE
J 0
(-8700 2000);
DISPLAY 0.872340 (-8700 2000);
PAINT GREEN (-8700 2000);
DISPLAY INVISIBLE (-8700 2000);
FORCEPROP 1 LAST COMMENT_BODY TRUE
J 0
(-8925 2050);
DISPLAY 0.872340 (-8925 2050);
PAINT GREEN (-8925 2050);
DISPLAY INVISIBLE (-8925 2050);
FORCEPROP 2 LAST PATH I187
J 0
(-8975 2200);
DISPLAY 1.021277 (-8975 2200);
DISPLAY INVISIBLE (-8975 2200);
FORCEADD Q_RES..1
R 2
(-8475 2125);
FORCEPROP 1 LAST LOCATION R301
J 2
(-8425 2175);
DISPLAY 0.489362 (-8425 2175);
PAINT SKYBLUE (-8425 2175);
FORCEPROP 0 LAST $SEC 1
J 0
(-8425 2225);
DISPLAY 0.680851 (-8425 2225);
PAINT MONO (-8425 2225);
DISPLAY INVISIBLE (-8425 2225);
FORCEPROP 0 LAST CDS_SEC 1
J 0
(-8425 2225);
DISPLAY 1.021277 (-8425 2225);
DISPLAY INVISIBLE (-8425 2225);
FORCEPROP 1 LASTPIN (-8375 2125) $PN 1
J 2
(-8387 2137);
DISPLAY 0.489362 (-8387 2137);
PAINT MONO (-8387 2137);
FORCEPROP 1 LASTPIN (-8575 2125) $PN 2
J 2
(-8537 2137);
DISPLAY 0.489362 (-8537 2137);
PAINT MONO (-8537 2137);
FORCEPROP 1 LAST VALUE 1K
J 0
(-8475 2075);
DISPLAY 0.489362 (-8475 2075);
PAINT SKYBLUE (-8475 2075);
FORCEPROP 1 LAST TOLERANCE 1%
J 2
(-8350 2100);
DISPLAY 0.489362 (-8350 2100);
PAINT SKYBLUE (-8350 2100);
DISPLAY INVISIBLE (-8350 2100);
FORCEPROP 2 LAST CDS_LIB pure_quanta
J 0
(-8475 2125);
DISPLAY INVISIBLE (-8475 2125);
FORCEPROP 2 LAST BOM_COST MEM
J 0
(-8500 2275);
DISPLAY 0.744681 (-8500 2275);
PAINT WHITE (-8500 2275);
DISPLAY INVISIBLE (-8500 2275);
FORCEPROP 1 LAST WATTAGE 1/16W
J 0
(-8400 2050);
DISPLAY 0.489362 (-8400 2050);
PAINT SKYBLUE (-8400 2050);
DISPLAY INVISIBLE (-8400 2050);
FORCEPROP 1 LAST MATERIAL CHIP
J 0
(-8650 2100);
DISPLAY 0.489362 (-8650 2100);
PAINT SKYBLUE (-8650 2100);
DISPLAY INVISIBLE (-8650 2100);
FORCEPROP 1 LAST PACK_TYPE 0402LF
J 0
(-8650 2050);
DISPLAY 0.489362 (-8650 2050);
PAINT SKYBLUE (-8650 2050);
DISPLAY INVISIBLE (-8650 2050);
FORCEPROP 2 LAST ROOM 
J 0
(-8500 2225);
DISPLAY 0.744681 (-8500 2225);
PAINT RED (-8500 2225);
DISPLAY INVISIBLE (-8500 2225);
FORCEPROP 1 LAST PATH I188
J 2
(-8425 2275);
DISPLAY 0.978723 (-8425 2275);
PAINT WHITE (-8425 2275);
DISPLAY INVISIBLE (-8425 2275);
FORCEPROP 1 LAST PART_NUMBER CS21002FB06
J 0
(-8575 2175);
DISPLAY 0.489362 (-8575 2175);
PAINT SKYBLUE (-8575 2175);
DISPLAY INVISIBLE (-8575 2175);
FORCEADD Q_RES..2
(-8350 2275);
FORCEPROP 1 LAST LOCATION R100
J 0
(-8305 2400);
DISPLAY 0.489362 (-8305 2400);
PAINT SKYBLUE (-8305 2400);
FORCEPROP 0 LAST $SEC 1
J 0
(-8300 2450);
DISPLAY 0.680851 (-8300 2450);
PAINT MONO (-8300 2450);
DISPLAY INVISIBLE (-8300 2450);
FORCEPROP 0 LAST CDS_SEC 1
J 0
(-8300 2450);
DISPLAY 1.021277 (-8300 2450);
DISPLAY INVISIBLE (-8300 2450);
FORCEPROP 1 LASTPIN (-8350 2375) $PN 1
J 0
(-8345 2337);
DISPLAY 0.489362 (-8345 2337);
PAINT MONO (-8345 2337);
FORCEPROP 1 LASTPIN (-8350 2175) $PN 2
J 0
(-8345 2185);
DISPLAY 0.489362 (-8345 2185);
PAINT MONO (-8345 2185);
FORCEPROP 1 LAST TOLERANCE 1%
J 0
(-8300 2325);
DISPLAY 0.489362 (-8300 2325);
PAINT SKYBLUE (-8300 2325);
FORCEPROP 1 LAST VALUE 1K
J 0
(-8305 2350);
DISPLAY 0.489362 (-8305 2350);
PAINT SKYBLUE (-8305 2350);
FORCEPROP 1 LAST PACK_TYPE 0402LF
J 0
(-8300 2225);
DISPLAY 0.489362 (-8300 2225);
PAINT SKYBLUE (-8300 2225);
FORCEPROP 1 LAST MATERIAL EMPTY
J 0
(-8300 2275);
DISPLAY 0.489362 (-8300 2275);
PAINT RED (-8300 2275);
FORCEPROP 1 LAST WATTAGE 1/16W
J 0
(-8300 2300);
DISPLAY 0.489362 (-8300 2300);
PAINT SKYBLUE (-8300 2300);
FORCEPROP 2 LAST CDS_LIB pure_quanta
J 0
(-8350 2275);
DISPLAY INVISIBLE (-8350 2275);
FORCEPROP 2 LAST BOM_COST MEM
J 0
(-8300 2450);
DISPLAY 0.808511 (-8300 2450);
DISPLAY INVISIBLE (-8300 2450);
FORCEPROP 2 LAST ROOM 
J 0
(-8300 2500);
DISPLAY 0.808511 (-8300 2500);
PAINT RED (-8300 2500);
DISPLAY INVISIBLE (-8300 2500);
FORCEPROP 1 LAST PATH I189
J 0
(-8300 2450);
DISPLAY 0.978723 (-8300 2450);
PAINT WHITE (-8300 2450);
DISPLAY INVISIBLE (-8300 2450);
FORCEPROP 1 LAST PART_NUMBER CS21002FB06
J 0
(-8300 2250);
DISPLAY 0.489362 (-8300 2250);
PAINT SKYBLUE (-8300 2250);
DISPLAY INVISIBLE (-8300 2250);
FORCEADD OFFPAGE..1
(-8325 4525);
FORCEPROP 2 LAST $XR0 20 
J 0
(-8546 4525);
DISPLAY 0.638298 (-8546 4525);
PAINT MONO (-8546 4525);
FORCEPROP 2 LAST CDS_LIB mstr_standard
J 0
(-8325 4525);
DISPLAY 0.808511 (-8325 4525);
DISPLAY INVISIBLE (-8325 4525);
FORCEPROP 1 LAST OFFPAGE TRUE
J 0
(-8000 4400);
DISPLAY 0.872340 (-8000 4400);
PAINT GREEN (-8000 4400);
DISPLAY INVISIBLE (-8000 4400);
FORCEPROP 1 LAST COMMENT_BODY TRUE
J 0
(-8200 4425);
DISPLAY 0.872340 (-8200 4425);
PAINT GREEN (-8200 4425);
DISPLAY INVISIBLE (-8200 4425);
FORCEPROP 2 LAST PATH I19
J 0
(-8275 4600);
DISPLAY 1.021277 (-8275 4600);
DISPLAY INVISIBLE (-8275 4600);
FORCEADD VCC_CORE..1
(-8350 2450);
FORCEPROP 3 LASTPIN (-8350 2400) SIG_NAME P3V3\g
J 0
(-8340 2410);
DISPLAY 0.659574 (-8340 2410);
PAINT MONO (-8340 2410);
DISPLAY INVISIBLE (-8340 2410);
FORCEPROP 1 LAST HDL_POWER P3V3
J 1
(-8350 2500);
DISPLAY 0.489362 (-8350 2500);
PAINT GREEN (-8350 2500);
FORCEPROP 2 LAST CDS_LIB mstr_symbols
J 0
(-8350 2450);
DISPLAY INVISIBLE (-8350 2450);
FORCEPROP 0 LAST VOLTAGE 3.3
J 0
(-8625 2600);
DISPLAY 1.021277 (-8625 2600);
PAINT SKYBLUE (-8625 2600);
DISPLAY INVISIBLE (-8625 2600);
FORCEPROP 2 LAST ROOM PVCCINFAON_CPU0_CTRL
J 0
(-8350 2550);
DISPLAY 0.808511 (-8350 2550);
PAINT RED (-8350 2550);
DISPLAY INVISIBLE (-8350 2550);
FORCEPROP 1 LAST PATH I190
J 0
(-8300 2475);
DISPLAY 0.872340 (-8300 2475);
PAINT AQUA (-8300 2475);
DISPLAY INVISIBLE (-8300 2475);
FORCEADD TAP..1
(-3275 3200);
FORCEPROP 3 LASTPIN (-3325 3200) SIG_NAME M_K_CPU0_SB_DQS_DN<6>
J 0
(-3315 3210);
DISPLAY 0.659574 (-3315 3210);
PAINT MONO (-3315 3210);
DISPLAY INVISIBLE (-3315 3210);
FORCEPROP 1 LASTPIN (-3325 3200) BN 6
J 0
(-3337 3208);
DISPLAY 0.489362 (-3337 3208);
PAINT GREEN (-3337 3208);
FORCEPROP 2 LAST CDS_LIB mstr_standard
J 0
(-3275 3200);
DISPLAY 0.723404 (-3275 3200);
PAINT MONO (-3275 3200);
DISPLAY INVISIBLE (-3275 3200);
FORCEPROP 1 LAST BODY_TYPE PLUMBING
J 0
(-3275 3250);
DISPLAY 0.872340 (-3275 3250);
PAINT GREEN (-3275 3250);
DISPLAY INVISIBLE (-3275 3250);
FORCEPROP 1 LAST HDL_TAP TRUE
J 0
(-2950 3075);
DISPLAY 0.872340 (-2950 3075);
DISPLAY INVISIBLE (-2950 3075);
FORCEPROP 1 LAST PATH I191
J 0
(-3277 3200);
DISPLAY 0.872340 (-3277 3200);
PAINT GREEN (-3277 3200);
DISPLAY INVISIBLE (-3277 3200);
FORCEADD TAP..1
(-3475 3250);
FORCEPROP 3 LASTPIN (-3525 3250) SIG_NAME M_K_CPU0_SB_DQS_DP<6>
J 0
(-3515 3260);
DISPLAY 0.659574 (-3515 3260);
PAINT MONO (-3515 3260);
DISPLAY INVISIBLE (-3515 3260);
FORCEPROP 1 LASTPIN (-3525 3250) BN 6
J 0
(-3537 3258);
DISPLAY 0.489362 (-3537 3258);
PAINT GREEN (-3537 3258);
FORCEPROP 2 LAST CDS_LIB mstr_standard
J 0
(-3475 3250);
DISPLAY 0.723404 (-3475 3250);
PAINT MONO (-3475 3250);
DISPLAY INVISIBLE (-3475 3250);
FORCEPROP 1 LAST BODY_TYPE PLUMBING
J 0
(-3475 3300);
DISPLAY 0.872340 (-3475 3300);
PAINT GREEN (-3475 3300);
DISPLAY INVISIBLE (-3475 3300);
FORCEPROP 1 LAST HDL_TAP TRUE
J 0
(-3150 3125);
DISPLAY 0.872340 (-3150 3125);
DISPLAY INVISIBLE (-3150 3125);
FORCEPROP 1 LAST PATH I192
J 0
(-3477 3250);
DISPLAY 0.872340 (-3477 3250);
PAINT GREEN (-3477 3250);
DISPLAY INVISIBLE (-3477 3250);
FORCEADD TAP..1
(-3475 3350);
FORCEPROP 3 LASTPIN (-3525 3350) SIG_NAME M_K_CPU0_SB_DQS_DP<7>
J 0
(-3515 3360);
DISPLAY 0.659574 (-3515 3360);
PAINT MONO (-3515 3360);
DISPLAY INVISIBLE (-3515 3360);
FORCEPROP 1 LASTPIN (-3525 3350) BN 7
J 0
(-3537 3358);
DISPLAY 0.489362 (-3537 3358);
PAINT GREEN (-3537 3358);
FORCEPROP 2 LAST CDS_LIB mstr_standard
J 0
(-3475 3350);
DISPLAY 0.723404 (-3475 3350);
PAINT MONO (-3475 3350);
DISPLAY INVISIBLE (-3475 3350);
FORCEPROP 1 LAST BODY_TYPE PLUMBING
J 0
(-3475 3400);
DISPLAY 0.872340 (-3475 3400);
PAINT GREEN (-3475 3400);
DISPLAY INVISIBLE (-3475 3400);
FORCEPROP 1 LAST HDL_TAP TRUE
J 0
(-3150 3225);
DISPLAY 0.872340 (-3150 3225);
DISPLAY INVISIBLE (-3150 3225);
FORCEPROP 1 LAST PATH I193
J 0
(-3477 3350);
DISPLAY 0.872340 (-3477 3350);
PAINT GREEN (-3477 3350);
DISPLAY INVISIBLE (-3477 3350);
FORCEADD OFFPAGE..2
(-2475 4650);
FORCEPROP 2 LAST $XR0 20 
J 0
(-2286 4650);
DISPLAY 0.638298 (-2286 4650);
PAINT MONO (-2286 4650);
FORCEPROP 2 LAST CDS_LIB mstr_standard
J 0
(-2475 4650);
DISPLAY 0.723404 (-2475 4650);
PAINT MONO (-2475 4650);
DISPLAY INVISIBLE (-2475 4650);
FORCEPROP 1 LAST OFFPAGE TRUE
J 0
(-2150 4525);
DISPLAY 0.723404 (-2150 4525);
PAINT GREEN (-2150 4525);
DISPLAY INVISIBLE (-2150 4525);
FORCEPROP 1 LAST COMMENT_BODY TRUE
J 0
(-2520 4555);
DISPLAY 0.872340 (-2520 4555);
PAINT GREEN (-2520 4555);
DISPLAY INVISIBLE (-2520 4555);
FORCEPROP 2 LAST PATH I195
J 0
(-2275 4700);
DISPLAY 0.680851 (-2275 4700);
DISPLAY INVISIBLE (-2275 4700);
FORCEADD OFFPAGE..2
(-2475 4600);
FORCEPROP 2 LAST $XR0 20 
J 0
(-2286 4600);
DISPLAY 0.638298 (-2286 4600);
PAINT MONO (-2286 4600);
FORCEPROP 2 LAST CDS_LIB mstr_standard
J 0
(-2475 4600);
DISPLAY 0.723404 (-2475 4600);
PAINT MONO (-2475 4600);
DISPLAY INVISIBLE (-2475 4600);
FORCEPROP 1 LAST OFFPAGE TRUE
J 0
(-2150 4475);
DISPLAY 0.723404 (-2150 4475);
PAINT GREEN (-2150 4475);
DISPLAY INVISIBLE (-2150 4475);
FORCEPROP 1 LAST COMMENT_BODY TRUE
J 0
(-2520 4505);
DISPLAY 0.872340 (-2520 4505);
PAINT GREEN (-2520 4505);
DISPLAY INVISIBLE (-2520 4505);
FORCEPROP 2 LAST PATH I196
J 0
(-2275 4650);
DISPLAY 0.680851 (-2275 4650);
DISPLAY INVISIBLE (-2275 4650);
FORCEADD OFFPAGE..2
(-2475 3600);
FORCEPROP 2 LAST $XR0 20 
J 0
(-2286 3600);
DISPLAY 0.638298 (-2286 3600);
PAINT MONO (-2286 3600);
FORCEPROP 2 LAST CDS_LIB mstr_standard
J 0
(-2475 3600);
DISPLAY 0.723404 (-2475 3600);
PAINT MONO (-2475 3600);
DISPLAY INVISIBLE (-2475 3600);
FORCEPROP 1 LAST OFFPAGE TRUE
J 0
(-2150 3475);
DISPLAY 0.723404 (-2150 3475);
PAINT GREEN (-2150 3475);
DISPLAY INVISIBLE (-2150 3475);
FORCEPROP 1 LAST COMMENT_BODY TRUE
J 0
(-2520 3505);
DISPLAY 0.872340 (-2520 3505);
PAINT GREEN (-2520 3505);
DISPLAY INVISIBLE (-2520 3505);
FORCEPROP 2 LAST PATH I197
J 0
(-2275 3650);
DISPLAY 0.680851 (-2275 3650);
DISPLAY INVISIBLE (-2275 3650);
FORCEADD OFFPAGE..2
(-2475 3550);
FORCEPROP 2 LAST $XR0 20 
J 0
(-2286 3550);
DISPLAY 0.638298 (-2286 3550);
PAINT MONO (-2286 3550);
FORCEPROP 2 LAST CDS_LIB mstr_standard
J 0
(-2475 3550);
DISPLAY 0.723404 (-2475 3550);
PAINT MONO (-2475 3550);
DISPLAY INVISIBLE (-2475 3550);
FORCEPROP 1 LAST OFFPAGE TRUE
J 0
(-2150 3425);
DISPLAY 0.723404 (-2150 3425);
PAINT GREEN (-2150 3425);
DISPLAY INVISIBLE (-2150 3425);
FORCEPROP 1 LAST COMMENT_BODY TRUE
J 0
(-2520 3455);
DISPLAY 0.872340 (-2520 3455);
PAINT GREEN (-2520 3455);
DISPLAY INVISIBLE (-2520 3455);
FORCEPROP 2 LAST PATH I198
J 0
(-2275 3600);
DISPLAY 0.680851 (-2275 3600);
DISPLAY INVISIBLE (-2275 3600);
FORCEADD TAP..1
(-3275 4550);
FORCEPROP 3 LASTPIN (-3325 4550) SIG_NAME M_K_CPU0_SA_DQS_DN<9>
J 0
(-3315 4560);
DISPLAY 0.659574 (-3315 4560);
PAINT MONO (-3315 4560);
DISPLAY INVISIBLE (-3315 4560);
FORCEPROP 1 LASTPIN (-3325 4550) BN 9
J 0
(-3337 4558);
DISPLAY 0.489362 (-3337 4558);
PAINT GREEN (-3337 4558);
FORCEPROP 2 LAST CDS_LIB mstr_standard
J 0
(-3275 4550);
DISPLAY 0.723404 (-3275 4550);
PAINT MONO (-3275 4550);
DISPLAY INVISIBLE (-3275 4550);
FORCEPROP 1 LAST BODY_TYPE PLUMBING
J 0
(-3275 4600);
DISPLAY 0.872340 (-3275 4600);
PAINT GREEN (-3275 4600);
DISPLAY INVISIBLE (-3275 4600);
FORCEPROP 1 LAST HDL_TAP TRUE
J 0
(-2950 4425);
DISPLAY 0.872340 (-2950 4425);
DISPLAY INVISIBLE (-2950 4425);
FORCEPROP 1 LAST PATH I199
J 0
(-3277 4550);
DISPLAY 0.872340 (-3277 4550);
PAINT GREEN (-3277 4550);
DISPLAY INVISIBLE (-3277 4550);
FORCEADD OFFPAGE..1
(-8325 5025);
FORCEPROP 2 LAST $XR0 20 
J 0
(-8546 5025);
DISPLAY 0.638298 (-8546 5025);
PAINT MONO (-8546 5025);
FORCEPROP 2 LAST CDS_LIB mstr_standard
J 0
(-8325 5025);
DISPLAY 0.723404 (-8325 5025);
PAINT MONO (-8325 5025);
DISPLAY INVISIBLE (-8325 5025);
FORCEPROP 1 LAST OFFPAGE TRUE
J 0
(-8000 4900);
DISPLAY 0.872340 (-8000 4900);
PAINT GREEN (-8000 4900);
DISPLAY INVISIBLE (-8000 4900);
FORCEPROP 1 LAST COMMENT_BODY TRUE
J 0
(-8200 4925);
DISPLAY 0.872340 (-8200 4925);
PAINT GREEN (-8200 4925);
DISPLAY INVISIBLE (-8200 4925);
FORCEPROP 2 LAST PATH I20
J 0
(-8275 5100);
DISPLAY 1.021277 (-8275 5100);
DISPLAY INVISIBLE (-8275 5100);
FORCEADD TAP..1
(-3275 4450);
FORCEPROP 3 LASTPIN (-3325 4450) SIG_NAME M_K_CPU0_SA_DQS_DN<8>
J 0
(-3315 4460);
DISPLAY 0.659574 (-3315 4460);
PAINT MONO (-3315 4460);
DISPLAY INVISIBLE (-3315 4460);
FORCEPROP 1 LASTPIN (-3325 4450) BN 8
J 0
(-3337 4458);
DISPLAY 0.489362 (-3337 4458);
PAINT GREEN (-3337 4458);
FORCEPROP 2 LAST CDS_LIB mstr_standard
J 0
(-3275 4450);
DISPLAY 0.723404 (-3275 4450);
PAINT MONO (-3275 4450);
DISPLAY INVISIBLE (-3275 4450);
FORCEPROP 1 LAST BODY_TYPE PLUMBING
J 0
(-3275 4500);
DISPLAY 0.872340 (-3275 4500);
PAINT GREEN (-3275 4500);
DISPLAY INVISIBLE (-3275 4500);
FORCEPROP 1 LAST HDL_TAP TRUE
J 0
(-2950 4325);
DISPLAY 0.872340 (-2950 4325);
DISPLAY INVISIBLE (-2950 4325);
FORCEPROP 1 LAST PATH I200
J 0
(-3277 4450);
DISPLAY 0.872340 (-3277 4450);
PAINT GREEN (-3277 4450);
DISPLAY INVISIBLE (-3277 4450);
FORCEADD TAP..1
(-3475 4600);
FORCEPROP 3 LASTPIN (-3525 4600) SIG_NAME M_K_CPU0_SA_DQS_DP<9>
J 0
(-3515 4610);
DISPLAY 0.659574 (-3515 4610);
PAINT MONO (-3515 4610);
DISPLAY INVISIBLE (-3515 4610);
FORCEPROP 1 LASTPIN (-3525 4600) BN 9
J 0
(-3537 4608);
DISPLAY 0.489362 (-3537 4608);
PAINT GREEN (-3537 4608);
FORCEPROP 2 LAST CDS_LIB mstr_standard
J 0
(-3475 4600);
DISPLAY 0.723404 (-3475 4600);
PAINT MONO (-3475 4600);
DISPLAY INVISIBLE (-3475 4600);
FORCEPROP 1 LAST BODY_TYPE PLUMBING
J 0
(-3475 4650);
DISPLAY 0.872340 (-3475 4650);
PAINT GREEN (-3475 4650);
DISPLAY INVISIBLE (-3475 4650);
FORCEPROP 1 LAST HDL_TAP TRUE
J 0
(-3150 4475);
DISPLAY 0.872340 (-3150 4475);
DISPLAY INVISIBLE (-3150 4475);
FORCEPROP 1 LAST PATH I201
J 0
(-3477 4600);
DISPLAY 0.872340 (-3477 4600);
PAINT GREEN (-3477 4600);
DISPLAY INVISIBLE (-3477 4600);
FORCEADD TAP..1
(-3475 4400);
FORCEPROP 3 LASTPIN (-3525 4400) SIG_NAME M_K_CPU0_SA_DQS_DP<7>
J 0
(-3515 4410);
DISPLAY 0.659574 (-3515 4410);
PAINT MONO (-3515 4410);
DISPLAY INVISIBLE (-3515 4410);
FORCEPROP 1 LASTPIN (-3525 4400) BN 7
J 0
(-3537 4408);
DISPLAY 0.489362 (-3537 4408);
PAINT GREEN (-3537 4408);
FORCEPROP 2 LAST CDS_LIB mstr_standard
J 0
(-3475 4400);
DISPLAY 0.723404 (-3475 4400);
PAINT MONO (-3475 4400);
DISPLAY INVISIBLE (-3475 4400);
FORCEPROP 1 LAST BODY_TYPE PLUMBING
J 0
(-3475 4450);
DISPLAY 0.872340 (-3475 4450);
PAINT GREEN (-3475 4450);
DISPLAY INVISIBLE (-3475 4450);
FORCEPROP 1 LAST HDL_TAP TRUE
J 0
(-3150 4275);
DISPLAY 0.872340 (-3150 4275);
DISPLAY INVISIBLE (-3150 4275);
FORCEPROP 1 LAST PATH I202
J 0
(-3477 4400);
DISPLAY 0.872340 (-3477 4400);
PAINT GREEN (-3477 4400);
DISPLAY INVISIBLE (-3477 4400);
FORCEADD TAP..1
(-3475 4500);
FORCEPROP 3 LASTPIN (-3525 4500) SIG_NAME M_K_CPU0_SA_DQS_DP<8>
J 0
(-3515 4510);
DISPLAY 0.659574 (-3515 4510);
PAINT MONO (-3515 4510);
DISPLAY INVISIBLE (-3515 4510);
FORCEPROP 1 LASTPIN (-3525 4500) BN 8
J 0
(-3537 4508);
DISPLAY 0.489362 (-3537 4508);
PAINT GREEN (-3537 4508);
FORCEPROP 2 LAST CDS_LIB mstr_standard
J 0
(-3475 4500);
DISPLAY 0.723404 (-3475 4500);
PAINT MONO (-3475 4500);
DISPLAY INVISIBLE (-3475 4500);
FORCEPROP 1 LAST BODY_TYPE PLUMBING
J 0
(-3475 4550);
DISPLAY 0.872340 (-3475 4550);
PAINT GREEN (-3475 4550);
DISPLAY INVISIBLE (-3475 4550);
FORCEPROP 1 LAST HDL_TAP TRUE
J 0
(-3150 4375);
DISPLAY 0.872340 (-3150 4375);
DISPLAY INVISIBLE (-3150 4375);
FORCEPROP 1 LAST PATH I203
J 0
(-3477 4500);
DISPLAY 0.872340 (-3477 4500);
PAINT GREEN (-3477 4500);
DISPLAY INVISIBLE (-3477 4500);
FORCEADD TAP..1
(-3275 4350);
FORCEPROP 3 LASTPIN (-3325 4350) SIG_NAME M_K_CPU0_SA_DQS_DN<7>
J 0
(-3315 4360);
DISPLAY 0.659574 (-3315 4360);
PAINT MONO (-3315 4360);
DISPLAY INVISIBLE (-3315 4360);
FORCEPROP 1 LASTPIN (-3325 4350) BN 7
J 0
(-3337 4358);
DISPLAY 0.489362 (-3337 4358);
PAINT GREEN (-3337 4358);
FORCEPROP 2 LAST CDS_LIB mstr_standard
J 0
(-3275 4350);
DISPLAY 0.723404 (-3275 4350);
PAINT MONO (-3275 4350);
DISPLAY INVISIBLE (-3275 4350);
FORCEPROP 1 LAST BODY_TYPE PLUMBING
J 0
(-3275 4400);
DISPLAY 0.872340 (-3275 4400);
PAINT GREEN (-3275 4400);
DISPLAY INVISIBLE (-3275 4400);
FORCEPROP 1 LAST HDL_TAP TRUE
J 0
(-2950 4225);
DISPLAY 0.872340 (-2950 4225);
DISPLAY INVISIBLE (-2950 4225);
FORCEPROP 1 LAST PATH I204
J 0
(-3277 4350);
DISPLAY 0.872340 (-3277 4350);
PAINT GREEN (-3277 4350);
DISPLAY INVISIBLE (-3277 4350);
FORCEADD TAP..1
(-3275 4150);
FORCEPROP 3 LASTPIN (-3325 4150) SIG_NAME M_K_CPU0_SA_DQS_DN<5>
J 0
(-3315 4160);
DISPLAY 0.659574 (-3315 4160);
PAINT MONO (-3315 4160);
DISPLAY INVISIBLE (-3315 4160);
FORCEPROP 1 LASTPIN (-3325 4150) BN 5
J 0
(-3337 4158);
DISPLAY 0.489362 (-3337 4158);
PAINT GREEN (-3337 4158);
FORCEPROP 2 LAST CDS_LIB mstr_standard
J 0
(-3275 4150);
DISPLAY 0.723404 (-3275 4150);
PAINT MONO (-3275 4150);
DISPLAY INVISIBLE (-3275 4150);
FORCEPROP 1 LAST BODY_TYPE PLUMBING
J 0
(-3275 4200);
DISPLAY 0.872340 (-3275 4200);
PAINT GREEN (-3275 4200);
DISPLAY INVISIBLE (-3275 4200);
FORCEPROP 1 LAST HDL_TAP TRUE
J 0
(-2950 4025);
DISPLAY 0.872340 (-2950 4025);
DISPLAY INVISIBLE (-2950 4025);
FORCEPROP 1 LAST PATH I205
J 0
(-3277 4150);
DISPLAY 0.872340 (-3277 4150);
PAINT GREEN (-3277 4150);
DISPLAY INVISIBLE (-3277 4150);
FORCEADD TAP..1
(-3275 4250);
FORCEPROP 3 LASTPIN (-3325 4250) SIG_NAME M_K_CPU0_SA_DQS_DN<6>
J 0
(-3315 4260);
DISPLAY 0.659574 (-3315 4260);
PAINT MONO (-3315 4260);
DISPLAY INVISIBLE (-3315 4260);
FORCEPROP 1 LASTPIN (-3325 4250) BN 6
J 0
(-3337 4258);
DISPLAY 0.489362 (-3337 4258);
PAINT GREEN (-3337 4258);
FORCEPROP 2 LAST CDS_LIB mstr_standard
J 0
(-3275 4250);
DISPLAY 0.723404 (-3275 4250);
PAINT MONO (-3275 4250);
DISPLAY INVISIBLE (-3275 4250);
FORCEPROP 1 LAST BODY_TYPE PLUMBING
J 0
(-3275 4300);
DISPLAY 0.872340 (-3275 4300);
PAINT GREEN (-3275 4300);
DISPLAY INVISIBLE (-3275 4300);
FORCEPROP 1 LAST HDL_TAP TRUE
J 0
(-2950 4125);
DISPLAY 0.872340 (-2950 4125);
DISPLAY INVISIBLE (-2950 4125);
FORCEPROP 1 LAST PATH I206
J 0
(-3277 4250);
DISPLAY 0.872340 (-3277 4250);
PAINT GREEN (-3277 4250);
DISPLAY INVISIBLE (-3277 4250);
FORCEADD TAP..1
(-3275 4050);
FORCEPROP 3 LASTPIN (-3325 4050) SIG_NAME M_K_CPU0_SA_DQS_DN<4>
J 0
(-3315 4060);
DISPLAY 0.659574 (-3315 4060);
PAINT MONO (-3315 4060);
DISPLAY INVISIBLE (-3315 4060);
FORCEPROP 1 LASTPIN (-3325 4050) BN 4
J 0
(-3337 4058);
DISPLAY 0.489362 (-3337 4058);
PAINT GREEN (-3337 4058);
FORCEPROP 2 LAST CDS_LIB mstr_standard
J 0
(-3275 4050);
DISPLAY 0.723404 (-3275 4050);
PAINT MONO (-3275 4050);
DISPLAY INVISIBLE (-3275 4050);
FORCEPROP 1 LAST BODY_TYPE PLUMBING
J 0
(-3275 4100);
DISPLAY 0.872340 (-3275 4100);
PAINT GREEN (-3275 4100);
DISPLAY INVISIBLE (-3275 4100);
FORCEPROP 1 LAST HDL_TAP TRUE
J 0
(-2950 3925);
DISPLAY 0.872340 (-2950 3925);
DISPLAY INVISIBLE (-2950 3925);
FORCEPROP 1 LAST PATH I207
J 0
(-3277 4050);
DISPLAY 0.872340 (-3277 4050);
PAINT GREEN (-3277 4050);
DISPLAY INVISIBLE (-3277 4050);
FORCEADD TAP..1
(-3275 3950);
FORCEPROP 3 LASTPIN (-3325 3950) SIG_NAME M_K_CPU0_SA_DQS_DN<3>
J 0
(-3315 3960);
DISPLAY 0.659574 (-3315 3960);
PAINT MONO (-3315 3960);
DISPLAY INVISIBLE (-3315 3960);
FORCEPROP 1 LASTPIN (-3325 3950) BN 3
J 0
(-3337 3958);
DISPLAY 0.489362 (-3337 3958);
PAINT GREEN (-3337 3958);
FORCEPROP 2 LAST CDS_LIB mstr_standard
J 0
(-3275 3950);
DISPLAY 0.723404 (-3275 3950);
PAINT MONO (-3275 3950);
DISPLAY INVISIBLE (-3275 3950);
FORCEPROP 1 LAST BODY_TYPE PLUMBING
J 0
(-3275 4000);
DISPLAY 0.872340 (-3275 4000);
PAINT GREEN (-3275 4000);
DISPLAY INVISIBLE (-3275 4000);
FORCEPROP 1 LAST HDL_TAP TRUE
J 0
(-2950 3825);
DISPLAY 0.872340 (-2950 3825);
DISPLAY INVISIBLE (-2950 3825);
FORCEPROP 1 LAST PATH I208
J 0
(-3277 3950);
DISPLAY 0.872340 (-3277 3950);
PAINT GREEN (-3277 3950);
DISPLAY INVISIBLE (-3277 3950);
FORCEADD TAP..1
(-3275 3850);
FORCEPROP 3 LASTPIN (-3325 3850) SIG_NAME M_K_CPU0_SA_DQS_DN<2>
J 0
(-3315 3860);
DISPLAY 0.659574 (-3315 3860);
PAINT MONO (-3315 3860);
DISPLAY INVISIBLE (-3315 3860);
FORCEPROP 1 LASTPIN (-3325 3850) BN 2
J 0
(-3337 3858);
DISPLAY 0.489362 (-3337 3858);
PAINT GREEN (-3337 3858);
FORCEPROP 2 LAST CDS_LIB mstr_standard
J 0
(-3275 3850);
DISPLAY 0.723404 (-3275 3850);
PAINT MONO (-3275 3850);
DISPLAY INVISIBLE (-3275 3850);
FORCEPROP 1 LAST BODY_TYPE PLUMBING
J 0
(-3275 3900);
DISPLAY 0.872340 (-3275 3900);
PAINT GREEN (-3275 3900);
DISPLAY INVISIBLE (-3275 3900);
FORCEPROP 1 LAST HDL_TAP TRUE
J 0
(-2950 3725);
DISPLAY 0.872340 (-2950 3725);
DISPLAY INVISIBLE (-2950 3725);
FORCEPROP 1 LAST PATH I209
J 0
(-3277 3850);
DISPLAY 0.872340 (-3277 3850);
PAINT GREEN (-3277 3850);
DISPLAY INVISIBLE (-3277 3850);
FORCEADD OFFPAGE..1
(-8325 5425);
FORCEPROP 2 LAST $XR0 20 
J 0
(-8546 5425);
DISPLAY 0.638298 (-8546 5425);
PAINT MONO (-8546 5425);
FORCEPROP 2 LAST CDS_LIB mstr_standard
J 0
(-8325 5425);
DISPLAY 0.723404 (-8325 5425);
PAINT MONO (-8325 5425);
DISPLAY INVISIBLE (-8325 5425);
FORCEPROP 1 LAST OFFPAGE TRUE
J 0
(-8000 5300);
DISPLAY 0.872340 (-8000 5300);
PAINT GREEN (-8000 5300);
DISPLAY INVISIBLE (-8000 5300);
FORCEPROP 1 LAST COMMENT_BODY TRUE
J 0
(-8200 5325);
DISPLAY 0.872340 (-8200 5325);
PAINT GREEN (-8200 5325);
DISPLAY INVISIBLE (-8200 5325);
FORCEPROP 2 LAST PATH I21
J 0
(-8275 5500);
DISPLAY 1.021277 (-8275 5500);
DISPLAY INVISIBLE (-8275 5500);
FORCEADD TAP..1
(-3275 3650);
FORCEPROP 3 LASTPIN (-3325 3650) SIG_NAME M_K_CPU0_SA_DQS_DN<0>
J 0
(-3315 3660);
DISPLAY 0.659574 (-3315 3660);
PAINT MONO (-3315 3660);
DISPLAY INVISIBLE (-3315 3660);
FORCEPROP 1 LASTPIN (-3325 3650) BN 0
J 0
(-3337 3658);
DISPLAY 0.489362 (-3337 3658);
PAINT GREEN (-3337 3658);
FORCEPROP 2 LAST CDS_LIB mstr_standard
J 0
(-3275 3650);
DISPLAY 0.723404 (-3275 3650);
PAINT MONO (-3275 3650);
DISPLAY INVISIBLE (-3275 3650);
FORCEPROP 1 LAST BODY_TYPE PLUMBING
J 0
(-3275 3700);
DISPLAY 0.872340 (-3275 3700);
PAINT GREEN (-3275 3700);
DISPLAY INVISIBLE (-3275 3700);
FORCEPROP 1 LAST HDL_TAP TRUE
J 0
(-2950 3525);
DISPLAY 0.872340 (-2950 3525);
DISPLAY INVISIBLE (-2950 3525);
FORCEPROP 1 LAST PATH I210
J 0
(-3277 3650);
DISPLAY 0.872340 (-3277 3650);
PAINT GREEN (-3277 3650);
DISPLAY INVISIBLE (-3277 3650);
FORCEADD TAP..1
(-3275 3750);
FORCEPROP 3 LASTPIN (-3325 3750) SIG_NAME M_K_CPU0_SA_DQS_DN<1>
J 0
(-3315 3760);
DISPLAY 0.659574 (-3315 3760);
PAINT MONO (-3315 3760);
DISPLAY INVISIBLE (-3315 3760);
FORCEPROP 1 LASTPIN (-3325 3750) BN 1
J 0
(-3337 3758);
DISPLAY 0.489362 (-3337 3758);
PAINT GREEN (-3337 3758);
FORCEPROP 2 LAST CDS_LIB mstr_standard
J 0
(-3275 3750);
DISPLAY 0.723404 (-3275 3750);
PAINT MONO (-3275 3750);
DISPLAY INVISIBLE (-3275 3750);
FORCEPROP 1 LAST BODY_TYPE PLUMBING
J 0
(-3275 3800);
DISPLAY 0.872340 (-3275 3800);
PAINT GREEN (-3275 3800);
DISPLAY INVISIBLE (-3275 3800);
FORCEPROP 1 LAST HDL_TAP TRUE
J 0
(-2950 3625);
DISPLAY 0.872340 (-2950 3625);
DISPLAY INVISIBLE (-2950 3625);
FORCEPROP 1 LAST PATH I211
J 0
(-3277 3750);
DISPLAY 0.872340 (-3277 3750);
PAINT GREEN (-3277 3750);
DISPLAY INVISIBLE (-3277 3750);
FORCEADD TAP..1
(-3275 3500);
FORCEPROP 3 LASTPIN (-3325 3500) SIG_NAME M_K_CPU0_SB_DQS_DN<9>
J 0
(-3315 3510);
DISPLAY 0.659574 (-3315 3510);
PAINT MONO (-3315 3510);
DISPLAY INVISIBLE (-3315 3510);
FORCEPROP 1 LASTPIN (-3325 3500) BN 9
J 0
(-3337 3508);
DISPLAY 0.489362 (-3337 3508);
PAINT GREEN (-3337 3508);
FORCEPROP 2 LAST CDS_LIB mstr_standard
J 0
(-3275 3500);
DISPLAY 0.723404 (-3275 3500);
PAINT MONO (-3275 3500);
DISPLAY INVISIBLE (-3275 3500);
FORCEPROP 1 LAST BODY_TYPE PLUMBING
J 0
(-3275 3550);
DISPLAY 0.872340 (-3275 3550);
PAINT GREEN (-3275 3550);
DISPLAY INVISIBLE (-3275 3550);
FORCEPROP 1 LAST HDL_TAP TRUE
J 0
(-2950 3375);
DISPLAY 0.872340 (-2950 3375);
DISPLAY INVISIBLE (-2950 3375);
FORCEPROP 1 LAST PATH I212
J 0
(-3277 3500);
DISPLAY 0.872340 (-3277 3500);
PAINT GREEN (-3277 3500);
DISPLAY INVISIBLE (-3277 3500);
FORCEADD TAP..1
(-3275 3400);
FORCEPROP 3 LASTPIN (-3325 3400) SIG_NAME M_K_CPU0_SB_DQS_DN<8>
J 0
(-3315 3410);
DISPLAY 0.659574 (-3315 3410);
PAINT MONO (-3315 3410);
DISPLAY INVISIBLE (-3315 3410);
FORCEPROP 1 LASTPIN (-3325 3400) BN 8
J 0
(-3337 3408);
DISPLAY 0.489362 (-3337 3408);
PAINT GREEN (-3337 3408);
FORCEPROP 2 LAST CDS_LIB mstr_standard
J 0
(-3275 3400);
DISPLAY 0.723404 (-3275 3400);
PAINT MONO (-3275 3400);
DISPLAY INVISIBLE (-3275 3400);
FORCEPROP 1 LAST BODY_TYPE PLUMBING
J 0
(-3275 3450);
DISPLAY 0.872340 (-3275 3450);
PAINT GREEN (-3275 3450);
DISPLAY INVISIBLE (-3275 3450);
FORCEPROP 1 LAST HDL_TAP TRUE
J 0
(-2950 3275);
DISPLAY 0.872340 (-2950 3275);
DISPLAY INVISIBLE (-2950 3275);
FORCEPROP 1 LAST PATH I213
J 0
(-3277 3400);
DISPLAY 0.872340 (-3277 3400);
PAINT GREEN (-3277 3400);
DISPLAY INVISIBLE (-3277 3400);
FORCEADD TAP..1
(-3475 4300);
FORCEPROP 3 LASTPIN (-3525 4300) SIG_NAME M_K_CPU0_SA_DQS_DP<6>
J 0
(-3515 4310);
DISPLAY 0.659574 (-3515 4310);
PAINT MONO (-3515 4310);
DISPLAY INVISIBLE (-3515 4310);
FORCEPROP 1 LASTPIN (-3525 4300) BN 6
J 0
(-3537 4308);
DISPLAY 0.489362 (-3537 4308);
PAINT GREEN (-3537 4308);
FORCEPROP 2 LAST CDS_LIB mstr_standard
J 0
(-3475 4300);
DISPLAY 0.723404 (-3475 4300);
PAINT MONO (-3475 4300);
DISPLAY INVISIBLE (-3475 4300);
FORCEPROP 1 LAST BODY_TYPE PLUMBING
J 0
(-3475 4350);
DISPLAY 0.872340 (-3475 4350);
PAINT GREEN (-3475 4350);
DISPLAY INVISIBLE (-3475 4350);
FORCEPROP 1 LAST HDL_TAP TRUE
J 0
(-3150 4175);
DISPLAY 0.872340 (-3150 4175);
DISPLAY INVISIBLE (-3150 4175);
FORCEPROP 1 LAST PATH I214
J 0
(-3477 4300);
DISPLAY 0.872340 (-3477 4300);
PAINT GREEN (-3477 4300);
DISPLAY INVISIBLE (-3477 4300);
FORCEADD TAP..1
(-3475 4200);
FORCEPROP 3 LASTPIN (-3525 4200) SIG_NAME M_K_CPU0_SA_DQS_DP<5>
J 0
(-3515 4210);
DISPLAY 0.659574 (-3515 4210);
PAINT MONO (-3515 4210);
DISPLAY INVISIBLE (-3515 4210);
FORCEPROP 1 LASTPIN (-3525 4200) BN 5
J 0
(-3537 4208);
DISPLAY 0.489362 (-3537 4208);
PAINT GREEN (-3537 4208);
FORCEPROP 2 LAST CDS_LIB mstr_standard
J 0
(-3475 4200);
DISPLAY 0.723404 (-3475 4200);
PAINT MONO (-3475 4200);
DISPLAY INVISIBLE (-3475 4200);
FORCEPROP 1 LAST BODY_TYPE PLUMBING
J 0
(-3475 4250);
DISPLAY 0.872340 (-3475 4250);
PAINT GREEN (-3475 4250);
DISPLAY INVISIBLE (-3475 4250);
FORCEPROP 1 LAST HDL_TAP TRUE
J 0
(-3150 4075);
DISPLAY 0.872340 (-3150 4075);
DISPLAY INVISIBLE (-3150 4075);
FORCEPROP 1 LAST PATH I215
J 0
(-3477 4200);
DISPLAY 0.872340 (-3477 4200);
PAINT GREEN (-3477 4200);
DISPLAY INVISIBLE (-3477 4200);
FORCEADD TAP..1
(-3475 4100);
FORCEPROP 3 LASTPIN (-3525 4100) SIG_NAME M_K_CPU0_SA_DQS_DP<4>
J 0
(-3515 4110);
DISPLAY 0.659574 (-3515 4110);
PAINT MONO (-3515 4110);
DISPLAY INVISIBLE (-3515 4110);
FORCEPROP 1 LASTPIN (-3525 4100) BN 4
J 0
(-3537 4108);
DISPLAY 0.489362 (-3537 4108);
PAINT GREEN (-3537 4108);
FORCEPROP 2 LAST CDS_LIB mstr_standard
J 0
(-3475 4100);
DISPLAY 0.723404 (-3475 4100);
PAINT MONO (-3475 4100);
DISPLAY INVISIBLE (-3475 4100);
FORCEPROP 1 LAST BODY_TYPE PLUMBING
J 0
(-3475 4150);
DISPLAY 0.872340 (-3475 4150);
PAINT GREEN (-3475 4150);
DISPLAY INVISIBLE (-3475 4150);
FORCEPROP 1 LAST HDL_TAP TRUE
J 0
(-3150 3975);
DISPLAY 0.872340 (-3150 3975);
DISPLAY INVISIBLE (-3150 3975);
FORCEPROP 1 LAST PATH I216
J 0
(-3477 4100);
DISPLAY 0.872340 (-3477 4100);
PAINT GREEN (-3477 4100);
DISPLAY INVISIBLE (-3477 4100);
FORCEADD TAP..1
(-3475 3900);
FORCEPROP 3 LASTPIN (-3525 3900) SIG_NAME M_K_CPU0_SA_DQS_DP<2>
J 0
(-3515 3910);
DISPLAY 0.659574 (-3515 3910);
PAINT MONO (-3515 3910);
DISPLAY INVISIBLE (-3515 3910);
FORCEPROP 1 LASTPIN (-3525 3900) BN 2
J 0
(-3537 3908);
DISPLAY 0.489362 (-3537 3908);
PAINT GREEN (-3537 3908);
FORCEPROP 2 LAST CDS_LIB mstr_standard
J 0
(-3475 3900);
DISPLAY 0.723404 (-3475 3900);
PAINT MONO (-3475 3900);
DISPLAY INVISIBLE (-3475 3900);
FORCEPROP 1 LAST BODY_TYPE PLUMBING
J 0
(-3475 3950);
DISPLAY 0.872340 (-3475 3950);
PAINT GREEN (-3475 3950);
DISPLAY INVISIBLE (-3475 3950);
FORCEPROP 1 LAST HDL_TAP TRUE
J 0
(-3150 3775);
DISPLAY 0.872340 (-3150 3775);
DISPLAY INVISIBLE (-3150 3775);
FORCEPROP 1 LAST PATH I217
J 0
(-3477 3900);
DISPLAY 0.872340 (-3477 3900);
PAINT GREEN (-3477 3900);
DISPLAY INVISIBLE (-3477 3900);
FORCEADD TAP..1
(-3475 4000);
FORCEPROP 3 LASTPIN (-3525 4000) SIG_NAME M_K_CPU0_SA_DQS_DP<3>
J 0
(-3515 4010);
DISPLAY 0.659574 (-3515 4010);
PAINT MONO (-3515 4010);
DISPLAY INVISIBLE (-3515 4010);
FORCEPROP 1 LASTPIN (-3525 4000) BN 3
J 0
(-3537 4008);
DISPLAY 0.489362 (-3537 4008);
PAINT GREEN (-3537 4008);
FORCEPROP 2 LAST CDS_LIB mstr_standard
J 0
(-3475 4000);
DISPLAY 0.723404 (-3475 4000);
PAINT MONO (-3475 4000);
DISPLAY INVISIBLE (-3475 4000);
FORCEPROP 1 LAST BODY_TYPE PLUMBING
J 0
(-3475 4050);
DISPLAY 0.872340 (-3475 4050);
PAINT GREEN (-3475 4050);
DISPLAY INVISIBLE (-3475 4050);
FORCEPROP 1 LAST HDL_TAP TRUE
J 0
(-3150 3875);
DISPLAY 0.872340 (-3150 3875);
DISPLAY INVISIBLE (-3150 3875);
FORCEPROP 1 LAST PATH I218
J 0
(-3477 4000);
DISPLAY 0.872340 (-3477 4000);
PAINT GREEN (-3477 4000);
DISPLAY INVISIBLE (-3477 4000);
FORCEADD TAP..1
(-3475 3800);
FORCEPROP 3 LASTPIN (-3525 3800) SIG_NAME M_K_CPU0_SA_DQS_DP<1>
J 0
(-3515 3810);
DISPLAY 0.659574 (-3515 3810);
PAINT MONO (-3515 3810);
DISPLAY INVISIBLE (-3515 3810);
FORCEPROP 1 LASTPIN (-3525 3800) BN 1
J 0
(-3537 3808);
DISPLAY 0.489362 (-3537 3808);
PAINT GREEN (-3537 3808);
FORCEPROP 2 LAST CDS_LIB mstr_standard
J 0
(-3475 3800);
DISPLAY 0.723404 (-3475 3800);
PAINT MONO (-3475 3800);
DISPLAY INVISIBLE (-3475 3800);
FORCEPROP 1 LAST BODY_TYPE PLUMBING
J 0
(-3475 3850);
DISPLAY 0.872340 (-3475 3850);
PAINT GREEN (-3475 3850);
DISPLAY INVISIBLE (-3475 3850);
FORCEPROP 1 LAST HDL_TAP TRUE
J 0
(-3150 3675);
DISPLAY 0.872340 (-3150 3675);
DISPLAY INVISIBLE (-3150 3675);
FORCEPROP 1 LAST PATH I219
J 0
(-3477 3800);
DISPLAY 0.872340 (-3477 3800);
PAINT GREEN (-3477 3800);
DISPLAY INVISIBLE (-3477 3800);
FORCEADD SCONN288_DDR506112002KQ..1
(-6875 3625);
FORCEPROP 1 LAST LOCATION J20
J 0
(-7325 5700);
DISPLAY 0.468085 (-7325 5700);
PAINT SKYBLUE (-7325 5700);
FORCEPROP 0 LAST $SEC 1
J 0
(-7325 5850);
DISPLAY 0.680851 (-7325 5850);
PAINT MONO (-7325 5850);
DISPLAY INVISIBLE (-7325 5850);
FORCEPROP 2 LAST CDS_SEC 1
J 0
(-7325 5850);
DISPLAY 1.021277 (-7325 5850);
DISPLAY INVISIBLE (-7325 5850);
FORCEPROP 0 LASTPIN (-7475 3025) $PN 62
J 2
(-7485 3035);
DISPLAY 0.680851 (-7485 3035);
PAINT MONO (-7485 3035);
FORCEPROP 0 LASTPIN (-7475 5075) $PN 66
J 2
(-7485 5085);
DISPLAY 0.680851 (-7485 5085);
PAINT MONO (-7485 5085);
FORCEPROP 0 LASTPIN (-7475 4675) $PN 76
J 2
(-7485 4685);
DISPLAY 0.680851 (-7485 4685);
PAINT MONO (-7485 4685);
FORCEPROP 0 LASTPIN (-7475 5125) $PN 211
J 2
(-7485 5135);
DISPLAY 0.680851 (-7485 5135);
PAINT MONO (-7485 5135);
FORCEPROP 0 LASTPIN (-7475 4725) $PN 221
J 2
(-7485 4735);
DISPLAY 0.680851 (-7485 4735);
PAINT MONO (-7485 4735);
FORCEPROP 0 LASTPIN (-7475 5175) $PN 68
J 2
(-7485 5185);
DISPLAY 0.680851 (-7485 5185);
PAINT MONO (-7485 5185);
FORCEPROP 0 LASTPIN (-7475 4775) $PN 78
J 2
(-7485 4785);
DISPLAY 0.680851 (-7485 4785);
PAINT MONO (-7485 4785);
FORCEPROP 0 LASTPIN (-7475 5225) $PN 213
J 2
(-7485 5235);
DISPLAY 0.680851 (-7485 5235);
PAINT MONO (-7485 5235);
FORCEPROP 0 LASTPIN (-7475 4825) $PN 223
J 2
(-7485 4835);
DISPLAY 0.680851 (-7485 4835);
PAINT MONO (-7485 4835);
FORCEPROP 0 LASTPIN (-7475 5275) $PN 70
J 2
(-7485 5285);
DISPLAY 0.680851 (-7485 5285);
PAINT MONO (-7485 5285);
FORCEPROP 0 LASTPIN (-7475 4875) $PN 80
J 2
(-7485 4885);
DISPLAY 0.680851 (-7485 4885);
PAINT MONO (-7485 4885);
FORCEPROP 0 LASTPIN (-7475 5325) $PN 215
J 2
(-7485 5335);
DISPLAY 0.680851 (-7485 5335);
PAINT MONO (-7485 5335);
FORCEPROP 0 LASTPIN (-7475 4925) $PN 225
J 2
(-7485 4935);
DISPLAY 0.680851 (-7485 4935);
PAINT MONO (-7485 4935);
FORCEPROP 0 LASTPIN (-7475 5375) $PN 72
J 2
(-7485 5385);
DISPLAY 0.680851 (-7485 5385);
PAINT MONO (-7485 5385);
FORCEPROP 0 LASTPIN (-7475 4975) $PN 82
J 2
(-7485 4985);
DISPLAY 0.680851 (-7485 4985);
PAINT MONO (-7485 4985);
FORCEPROP 0 LASTPIN (-7475 3625) $PN 51
J 2
(-7485 3635);
DISPLAY 0.680851 (-7485 3635);
PAINT MONO (-7485 3635);
FORCEPROP 0 LASTPIN (-7475 3175) $PN 96
J 2
(-7485 3185);
DISPLAY 0.680851 (-7485 3185);
PAINT MONO (-7485 3185);
FORCEPROP 0 LASTPIN (-7475 3675) $PN 53
J 2
(-7485 3685);
DISPLAY 0.680851 (-7485 3685);
PAINT MONO (-7485 3685);
FORCEPROP 0 LASTPIN (-7475 3225) $PN 98
J 2
(-7485 3235);
DISPLAY 0.680851 (-7485 3235);
PAINT MONO (-7485 3235);
FORCEPROP 0 LASTPIN (-7475 3725) $PN 196
J 2
(-7485 3735);
DISPLAY 0.680851 (-7485 3735);
PAINT MONO (-7485 3735);
FORCEPROP 0 LASTPIN (-7475 3275) $PN 241
J 2
(-7485 3285);
DISPLAY 0.680851 (-7485 3285);
PAINT MONO (-7485 3285);
FORCEPROP 0 LASTPIN (-7475 3775) $PN 198
J 2
(-7485 3785);
DISPLAY 0.680851 (-7485 3785);
PAINT MONO (-7485 3785);
FORCEPROP 0 LASTPIN (-7475 3325) $PN 243
J 2
(-7485 3335);
DISPLAY 0.680851 (-7485 3335);
PAINT MONO (-7485 3335);
FORCEPROP 0 LASTPIN (-7475 3825) $PN 58
J 2
(-7485 3835);
DISPLAY 0.680851 (-7485 3835);
PAINT MONO (-7485 3835);
FORCEPROP 0 LASTPIN (-7475 3375) $PN 89
J 2
(-7485 3385);
DISPLAY 0.680851 (-7485 3385);
PAINT MONO (-7485 3385);
FORCEPROP 0 LASTPIN (-7475 3875) $PN 60
J 2
(-7485 3885);
DISPLAY 0.680851 (-7485 3885);
PAINT MONO (-7485 3885);
FORCEPROP 0 LASTPIN (-7475 3425) $PN 91
J 2
(-7485 3435);
DISPLAY 0.680851 (-7485 3435);
PAINT MONO (-7485 3435);
FORCEPROP 0 LASTPIN (-7475 3925) $PN 203
J 2
(-7485 3935);
DISPLAY 0.680851 (-7485 3935);
PAINT MONO (-7485 3935);
FORCEPROP 0 LASTPIN (-7475 3475) $PN 234
J 2
(-7485 3485);
DISPLAY 0.680851 (-7485 3485);
PAINT MONO (-7485 3485);
FORCEPROP 0 LASTPIN (-7475 3975) $PN 205
J 2
(-7485 3985);
DISPLAY 0.680851 (-7485 3985);
PAINT MONO (-7485 3985);
FORCEPROP 0 LASTPIN (-7475 3525) $PN 236
J 2
(-7485 3535);
DISPLAY 0.680851 (-7485 3535);
PAINT MONO (-7485 3535);
FORCEPROP 0 LASTPIN (-7475 4075) $PN 218
J 2
(-7485 4085);
DISPLAY 0.680851 (-7485 4085);
PAINT MONO (-7485 4085);
FORCEPROP 0 LASTPIN (-7475 4125) $PN 217
J 2
(-7485 4135);
DISPLAY 0.680851 (-7485 4135);
PAINT MONO (-7485 4135);
FORCEPROP 0 LASTPIN (-7475 4375) $PN 64
J 2
(-7485 4385);
DISPLAY 0.680851 (-7485 4385);
PAINT MONO (-7485 4385);
FORCEPROP 0 LASTPIN (-7475 4225) $PN 84
J 2
(-7485 4235);
DISPLAY 0.680851 (-7485 4235);
PAINT MONO (-7485 4235);
FORCEPROP 0 LASTPIN (-7475 4425) $PN 209
J 2
(-7485 4435);
DISPLAY 0.680851 (-7485 4435);
PAINT MONO (-7485 4435);
FORCEPROP 0 LASTPIN (-7475 4275) $PN 229
J 2
(-7485 4285);
DISPLAY 0.680851 (-7485 4285);
PAINT MONO (-7485 4285);
FORCEPROP 0 LASTPIN (-6275 3825) $PN 7
J 0
(-6265 3835);
DISPLAY 0.680851 (-6265 3835);
PAINT MONO (-6265 3835);
FORCEPROP 0 LASTPIN (-6275 2175) $PN 100
J 0
(-6265 2185);
DISPLAY 0.680851 (-6265 2185);
PAINT MONO (-6265 2185);
FORCEPROP 0 LASTPIN (-6275 3875) $PN 9
J 0
(-6265 3885);
DISPLAY 0.680851 (-6265 3885);
PAINT MONO (-6265 3885);
FORCEPROP 0 LASTPIN (-6275 2225) $PN 102
J 0
(-6265 2235);
DISPLAY 0.680851 (-6265 2235);
PAINT MONO (-6265 2235);
FORCEPROP 0 LASTPIN (-6275 3925) $PN 152
J 0
(-6265 3935);
DISPLAY 0.680851 (-6265 3935);
PAINT MONO (-6265 3935);
FORCEPROP 0 LASTPIN (-6275 2275) $PN 245
J 0
(-6265 2285);
DISPLAY 0.680851 (-6265 2285);
PAINT MONO (-6265 2285);
FORCEPROP 0 LASTPIN (-6275 3975) $PN 154
J 0
(-6265 3985);
DISPLAY 0.680851 (-6265 3985);
PAINT MONO (-6265 3985);
FORCEPROP 0 LASTPIN (-6275 2325) $PN 247
J 0
(-6265 2335);
DISPLAY 0.680851 (-6265 2335);
PAINT MONO (-6265 2335);
FORCEPROP 0 LASTPIN (-6275 4025) $PN 14
J 0
(-6265 4035);
DISPLAY 0.680851 (-6265 4035);
PAINT MONO (-6265 4035);
FORCEPROP 0 LASTPIN (-6275 2375) $PN 107
J 0
(-6265 2385);
DISPLAY 0.680851 (-6265 2385);
PAINT MONO (-6265 2385);
FORCEPROP 0 LASTPIN (-6275 4075) $PN 16
J 0
(-6265 4085);
DISPLAY 0.680851 (-6265 4085);
PAINT MONO (-6265 4085);
FORCEPROP 0 LASTPIN (-6275 2425) $PN 109
J 0
(-6265 2435);
DISPLAY 0.680851 (-6265 2435);
PAINT MONO (-6265 2435);
FORCEPROP 0 LASTPIN (-6275 4125) $PN 159
J 0
(-6265 4135);
DISPLAY 0.680851 (-6265 4135);
PAINT MONO (-6265 4135);
FORCEPROP 0 LASTPIN (-6275 2475) $PN 252
J 0
(-6265 2485);
DISPLAY 0.680851 (-6265 2485);
PAINT MONO (-6265 2485);
FORCEPROP 0 LASTPIN (-6275 4175) $PN 161
J 0
(-6265 4185);
DISPLAY 0.680851 (-6265 4185);
PAINT MONO (-6265 4185);
FORCEPROP 0 LASTPIN (-6275 2525) $PN 254
J 0
(-6265 2535);
DISPLAY 0.680851 (-6265 2535);
PAINT MONO (-6265 2535);
FORCEPROP 0 LASTPIN (-6275 4225) $PN 18
J 0
(-6265 4235);
DISPLAY 0.680851 (-6265 4235);
PAINT MONO (-6265 4235);
FORCEPROP 0 LASTPIN (-6275 2575) $PN 111
J 0
(-6265 2585);
DISPLAY 0.680851 (-6265 2585);
PAINT MONO (-6265 2585);
FORCEPROP 0 LASTPIN (-6275 4275) $PN 20
J 0
(-6265 4285);
DISPLAY 0.680851 (-6265 4285);
PAINT MONO (-6265 4285);
FORCEPROP 0 LASTPIN (-6275 2625) $PN 113
J 0
(-6265 2635);
DISPLAY 0.680851 (-6265 2635);
PAINT MONO (-6265 2635);
FORCEPROP 0 LASTPIN (-6275 4325) $PN 163
J 0
(-6265 4335);
DISPLAY 0.680851 (-6265 4335);
PAINT MONO (-6265 4335);
FORCEPROP 0 LASTPIN (-6275 2675) $PN 256
J 0
(-6265 2685);
DISPLAY 0.680851 (-6265 2685);
PAINT MONO (-6265 2685);
FORCEPROP 0 LASTPIN (-6275 4375) $PN 165
J 0
(-6265 4385);
DISPLAY 0.680851 (-6265 4385);
PAINT MONO (-6265 4385);
FORCEPROP 0 LASTPIN (-6275 2725) $PN 258
J 0
(-6265 2735);
DISPLAY 0.680851 (-6265 2735);
PAINT MONO (-6265 2735);
FORCEPROP 0 LASTPIN (-6275 4425) $PN 25
J 0
(-6265 4435);
DISPLAY 0.680851 (-6265 4435);
PAINT MONO (-6265 4435);
FORCEPROP 0 LASTPIN (-6275 2775) $PN 118
J 0
(-6265 2785);
DISPLAY 0.680851 (-6265 2785);
PAINT MONO (-6265 2785);
FORCEPROP 0 LASTPIN (-6275 4475) $PN 27
J 0
(-6265 4485);
DISPLAY 0.680851 (-6265 4485);
PAINT MONO (-6265 4485);
FORCEPROP 0 LASTPIN (-6275 2825) $PN 120
J 0
(-6265 2835);
DISPLAY 0.680851 (-6265 2835);
PAINT MONO (-6265 2835);
FORCEPROP 0 LASTPIN (-6275 4525) $PN 170
J 0
(-6265 4535);
DISPLAY 0.680851 (-6265 4535);
PAINT MONO (-6265 4535);
FORCEPROP 0 LASTPIN (-6275 2875) $PN 263
J 0
(-6265 2885);
DISPLAY 0.680851 (-6265 2885);
PAINT MONO (-6265 2885);
FORCEPROP 0 LASTPIN (-6275 4575) $PN 172
J 0
(-6265 4585);
DISPLAY 0.680851 (-6265 4585);
PAINT MONO (-6265 4585);
FORCEPROP 0 LASTPIN (-6275 2925) $PN 265
J 0
(-6265 2935);
DISPLAY 0.680851 (-6265 2935);
PAINT MONO (-6265 2935);
FORCEPROP 0 LASTPIN (-6275 4625) $PN 29
J 0
(-6265 4635);
DISPLAY 0.680851 (-6265 4635);
PAINT MONO (-6265 4635);
FORCEPROP 0 LASTPIN (-6275 2975) $PN 122
J 0
(-6265 2985);
DISPLAY 0.680851 (-6265 2985);
PAINT MONO (-6265 2985);
FORCEPROP 0 LASTPIN (-6275 4675) $PN 31
J 0
(-6265 4685);
DISPLAY 0.680851 (-6265 4685);
PAINT MONO (-6265 4685);
FORCEPROP 0 LASTPIN (-6275 3025) $PN 124
J 0
(-6265 3035);
DISPLAY 0.680851 (-6265 3035);
PAINT MONO (-6265 3035);
FORCEPROP 0 LASTPIN (-6275 4725) $PN 174
J 0
(-6265 4735);
DISPLAY 0.680851 (-6265 4735);
PAINT MONO (-6265 4735);
FORCEPROP 0 LASTPIN (-6275 3075) $PN 267
J 0
(-6265 3085);
DISPLAY 0.680851 (-6265 3085);
PAINT MONO (-6265 3085);
FORCEPROP 0 LASTPIN (-6275 4775) $PN 176
J 0
(-6265 4785);
DISPLAY 0.680851 (-6265 4785);
PAINT MONO (-6265 4785);
FORCEPROP 0 LASTPIN (-6275 3125) $PN 269
J 0
(-6265 3135);
DISPLAY 0.680851 (-6265 3135);
PAINT MONO (-6265 3135);
FORCEPROP 0 LASTPIN (-6275 4825) $PN 36
J 0
(-6265 4835);
DISPLAY 0.680851 (-6265 4835);
PAINT MONO (-6265 4835);
FORCEPROP 0 LASTPIN (-6275 3175) $PN 129
J 0
(-6265 3185);
DISPLAY 0.680851 (-6265 3185);
PAINT MONO (-6265 3185);
FORCEPROP 0 LASTPIN (-6275 4875) $PN 38
J 0
(-6265 4885);
DISPLAY 0.680851 (-6265 4885);
PAINT MONO (-6265 4885);
FORCEPROP 0 LASTPIN (-6275 3225) $PN 131
J 0
(-6265 3235);
DISPLAY 0.680851 (-6265 3235);
PAINT MONO (-6265 3235);
FORCEPROP 0 LASTPIN (-6275 4925) $PN 181
J 0
(-6265 4935);
DISPLAY 0.680851 (-6265 4935);
PAINT MONO (-6265 4935);
FORCEPROP 0 LASTPIN (-6275 3275) $PN 274
J 0
(-6265 3285);
DISPLAY 0.680851 (-6265 3285);
PAINT MONO (-6265 3285);
FORCEPROP 0 LASTPIN (-6275 4975) $PN 183
J 0
(-6265 4985);
DISPLAY 0.680851 (-6265 4985);
PAINT MONO (-6265 4985);
FORCEPROP 0 LASTPIN (-6275 3325) $PN 276
J 0
(-6265 3335);
DISPLAY 0.680851 (-6265 3335);
PAINT MONO (-6265 3335);
FORCEPROP 0 LASTPIN (-6275 5025) $PN 40
J 0
(-6265 5035);
DISPLAY 0.680851 (-6265 5035);
PAINT MONO (-6265 5035);
FORCEPROP 0 LASTPIN (-6275 3375) $PN 133
J 0
(-6265 3385);
DISPLAY 0.680851 (-6265 3385);
PAINT MONO (-6265 3385);
FORCEPROP 0 LASTPIN (-6275 5075) $PN 42
J 0
(-6265 5085);
DISPLAY 0.680851 (-6265 5085);
PAINT MONO (-6265 5085);
FORCEPROP 0 LASTPIN (-6275 3425) $PN 135
J 0
(-6265 3435);
DISPLAY 0.680851 (-6265 3435);
PAINT MONO (-6265 3435);
FORCEPROP 0 LASTPIN (-6275 5125) $PN 185
J 0
(-6265 5135);
DISPLAY 0.680851 (-6265 5135);
PAINT MONO (-6265 5135);
FORCEPROP 0 LASTPIN (-6275 3475) $PN 278
J 0
(-6265 3485);
DISPLAY 0.680851 (-6265 3485);
PAINT MONO (-6265 3485);
FORCEPROP 0 LASTPIN (-6275 5175) $PN 187
J 0
(-6265 5185);
DISPLAY 0.680851 (-6265 5185);
PAINT MONO (-6265 5185);
FORCEPROP 0 LASTPIN (-6275 3525) $PN 280
J 0
(-6265 3535);
DISPLAY 0.680851 (-6265 3535);
PAINT MONO (-6265 3535);
FORCEPROP 0 LASTPIN (-6275 5225) $PN 47
J 0
(-6265 5235);
DISPLAY 0.680851 (-6265 5235);
PAINT MONO (-6265 5235);
FORCEPROP 0 LASTPIN (-6275 3575) $PN 140
J 0
(-6265 3585);
DISPLAY 0.680851 (-6265 3585);
PAINT MONO (-6265 3585);
FORCEPROP 0 LASTPIN (-6275 5275) $PN 49
J 0
(-6265 5285);
DISPLAY 0.680851 (-6265 5285);
PAINT MONO (-6265 5285);
FORCEPROP 0 LASTPIN (-6275 3625) $PN 142
J 0
(-6265 3635);
DISPLAY 0.680851 (-6265 3635);
PAINT MONO (-6265 3635);
FORCEPROP 0 LASTPIN (-6275 5325) $PN 192
J 0
(-6265 5335);
DISPLAY 0.680851 (-6265 5335);
PAINT MONO (-6265 5335);
FORCEPROP 0 LASTPIN (-6275 3675) $PN 285
J 0
(-6265 3685);
DISPLAY 0.680851 (-6265 3685);
PAINT MONO (-6265 3685);
FORCEPROP 0 LASTPIN (-6275 5375) $PN 194
J 0
(-6265 5385);
DISPLAY 0.680851 (-6265 5385);
PAINT MONO (-6265 5385);
FORCEPROP 0 LASTPIN (-6275 3725) $PN 287
J 0
(-6265 3735);
DISPLAY 0.680851 (-6265 3735);
PAINT MONO (-6265 3735);
FORCEPROP 0 LASTPIN (-7475 2875) $PN 148
J 2
(-7485 2885);
DISPLAY 0.680851 (-7485 2885);
PAINT MONO (-7485 2885);
FORCEPROP 0 LASTPIN (-7475 2775) $PN 4
J 2
(-7485 2785);
DISPLAY 0.680851 (-7485 2785);
PAINT MONO (-7485 2785);
FORCEPROP 0 LASTPIN (-7475 2825) $PN 5
J 2
(-7485 2835);
DISPLAY 0.680851 (-7485 2835);
PAINT MONO (-7485 2835);
FORCEPROP 0 LASTPIN (-7475 1975) $PN 86
J 2
(-7485 1985);
DISPLAY 0.680851 (-7485 1985);
PAINT MONO (-7485 1985);
FORCEPROP 0 LASTPIN (-7475 1925) $PN 87
J 2
(-7485 1935);
DISPLAY 0.680851 (-7485 1935);
PAINT MONO (-7485 1935);
FORCEPROP 0 LASTPIN (-7475 4575) $PN 74
J 2
(-7485 4585);
DISPLAY 0.680851 (-7485 4585);
PAINT MONO (-7485 4585);
FORCEPROP 0 LASTPIN (-7475 4525) $PN 227
J 2
(-7485 4535);
DISPLAY 0.680851 (-7485 4535);
PAINT MONO (-7485 4535);
FORCEPROP 0 LASTPIN (-7475 2525) $PN 147
J 2
(-7485 2535);
DISPLAY 0.680851 (-7485 2535);
PAINT MONO (-7485 2535);
FORCEPROP 0 LASTPIN (-7475 3075) $PN 207
J 2
(-7485 3085);
DISPLAY 0.680851 (-7485 3085);
PAINT MONO (-7485 3085);
FORCEPROP 0 LASTPIN (-7475 2125) $PN 2
J 2
(-7485 2135);
DISPLAY 0.680851 (-7485 2135);
PAINT MONO (-7485 2135);
FORCEPROP 0 LASTPIN (-7475 2175) $PN 144
J 2
(-7485 2185);
DISPLAY 0.680851 (-7485 2185);
PAINT MONO (-7485 2185);
FORCEPROP 0 LASTPIN (-7475 2225) $PN 149
J 2
(-7485 2235);
DISPLAY 0.680851 (-7485 2235);
PAINT MONO (-7485 2235);
FORCEPROP 0 LASTPIN (-7475 2275) $PN 150
J 2
(-7485 2285);
DISPLAY 0.680851 (-7485 2285);
PAINT MONO (-7485 2285);
FORCEPROP 0 LASTPIN (-7475 2325) $PN 220
J 2
(-7485 2335);
DISPLAY 0.680851 (-7485 2335);
PAINT MONO (-7485 2335);
FORCEPROP 0 LASTPIN (-7475 2375) $PN 231
J 2
(-7485 2385);
DISPLAY 0.680851 (-7485 2385);
PAINT MONO (-7485 2385);
FORCEPROP 0 LASTPIN (-7475 2425) $PN 232
J 2
(-7485 2435);
DISPLAY 0.680851 (-7485 2435);
PAINT MONO (-7485 2435);
FORCEPROP 0 LASTPIN (-7475 2925) $PN 3
J 2
(-7485 2935);
DISPLAY 0.680851 (-7485 2935);
PAINT MONO (-7485 2935);
FORCEPROP 2 LAST PART_TYPE SMLF
J 0
(-7325 5800);
DISPLAY 1.021277 (-7325 5800);
FORCEPROP 2 LAST VALUE SCONN288_DDR506112002KQ
J 0
(-7325 5750);
DISPLAY 0.489362 (-7325 5750);
PAINT SKYBLUE (-7325 5750);
FORCEPROP 1 LAST MATERIAL IO
J 0
(-7325 5550);
DISPLAY 0.468085 (-7325 5550);
PAINT SKYBLUE (-7325 5550);
FORCEPROP 1 LAST CDS_LMAN_SYM_OUTLINE -450,1900,450,-1850
J 0
(-6875 3625);
DISPLAY 0.468085 (-6875 3625);
PAINT GREEN (-6875 3625);
DISPLAY INVISIBLE (-6875 3625);
FORCEPROP 1 LAST NEEDS_NO_SIZE TRUE
J 0
(-6875 3625);
DISPLAY 0.723404 (-6875 3625);
PAINT GREEN (-6875 3625);
DISPLAY INVISIBLE (-6875 3625);
FORCEPROP 2 LAST CDS_LIB pure_quanta
J 0
(-6875 3625);
DISPLAY INVISIBLE (-6875 3625);
FORCEPROP 1 LAST PATH I22
J 0
(-6875 3625);
DISPLAY 0.723404 (-6875 3625);
PAINT GREEN (-6875 3625);
DISPLAY INVISIBLE (-6875 3625);
FORCEPROP 1 LAST PART_NUMBER DFHST8FS479
J 0
(-7325 5625);
DISPLAY 0.468085 (-7325 5625);
PAINT SKYBLUE (-7325 5625);
DISPLAY INVISIBLE (-7325 5625);
FORCEADD TAP..1
(-3475 3700);
FORCEPROP 3 LASTPIN (-3525 3700) SIG_NAME M_K_CPU0_SA_DQS_DP<0>
J 0
(-3515 3710);
DISPLAY 0.659574 (-3515 3710);
PAINT MONO (-3515 3710);
DISPLAY INVISIBLE (-3515 3710);
FORCEPROP 1 LASTPIN (-3525 3700) BN 0
J 0
(-3537 3708);
DISPLAY 0.489362 (-3537 3708);
PAINT GREEN (-3537 3708);
FORCEPROP 2 LAST CDS_LIB mstr_standard
J 0
(-3475 3700);
DISPLAY 0.723404 (-3475 3700);
PAINT MONO (-3475 3700);
DISPLAY INVISIBLE (-3475 3700);
FORCEPROP 1 LAST BODY_TYPE PLUMBING
J 0
(-3475 3750);
DISPLAY 0.872340 (-3475 3750);
PAINT GREEN (-3475 3750);
DISPLAY INVISIBLE (-3475 3750);
FORCEPROP 1 LAST HDL_TAP TRUE
J 0
(-3150 3575);
DISPLAY 0.872340 (-3150 3575);
DISPLAY INVISIBLE (-3150 3575);
FORCEPROP 1 LAST PATH I220
J 0
(-3477 3700);
DISPLAY 0.872340 (-3477 3700);
PAINT GREEN (-3477 3700);
DISPLAY INVISIBLE (-3477 3700);
FORCEADD TAP..1
(-3475 3550);
FORCEPROP 3 LASTPIN (-3525 3550) SIG_NAME M_K_CPU0_SB_DQS_DP<9>
J 0
(-3515 3560);
DISPLAY 0.659574 (-3515 3560);
PAINT MONO (-3515 3560);
DISPLAY INVISIBLE (-3515 3560);
FORCEPROP 1 LASTPIN (-3525 3550) BN 9
J 0
(-3537 3558);
DISPLAY 0.489362 (-3537 3558);
PAINT GREEN (-3537 3558);
FORCEPROP 2 LAST CDS_LIB mstr_standard
J 0
(-3475 3550);
DISPLAY 0.723404 (-3475 3550);
PAINT MONO (-3475 3550);
DISPLAY INVISIBLE (-3475 3550);
FORCEPROP 1 LAST BODY_TYPE PLUMBING
J 0
(-3475 3600);
DISPLAY 0.872340 (-3475 3600);
PAINT GREEN (-3475 3600);
DISPLAY INVISIBLE (-3475 3600);
FORCEPROP 1 LAST HDL_TAP TRUE
J 0
(-3150 3425);
DISPLAY 0.872340 (-3150 3425);
DISPLAY INVISIBLE (-3150 3425);
FORCEPROP 1 LAST PATH I221
J 0
(-3477 3550);
DISPLAY 0.872340 (-3477 3550);
PAINT GREEN (-3477 3550);
DISPLAY INVISIBLE (-3477 3550);
FORCEADD TAP..1
(-3475 3450);
FORCEPROP 3 LASTPIN (-3525 3450) SIG_NAME M_K_CPU0_SB_DQS_DP<8>
J 0
(-3515 3460);
DISPLAY 0.659574 (-3515 3460);
PAINT MONO (-3515 3460);
DISPLAY INVISIBLE (-3515 3460);
FORCEPROP 1 LASTPIN (-3525 3450) BN 8
J 0
(-3537 3458);
DISPLAY 0.489362 (-3537 3458);
PAINT GREEN (-3537 3458);
FORCEPROP 2 LAST CDS_LIB mstr_standard
J 0
(-3475 3450);
DISPLAY 0.723404 (-3475 3450);
PAINT MONO (-3475 3450);
DISPLAY INVISIBLE (-3475 3450);
FORCEPROP 1 LAST BODY_TYPE PLUMBING
J 0
(-3475 3500);
DISPLAY 0.872340 (-3475 3500);
PAINT GREEN (-3475 3500);
DISPLAY INVISIBLE (-3475 3500);
FORCEPROP 1 LAST HDL_TAP TRUE
J 0
(-3150 3325);
DISPLAY 0.872340 (-3150 3325);
DISPLAY INVISIBLE (-3150 3325);
FORCEPROP 1 LAST PATH I222
J 0
(-3477 3450);
DISPLAY 0.872340 (-3477 3450);
PAINT GREEN (-3477 3450);
DISPLAY INVISIBLE (-3477 3450);
FORCEADD TAP..1
(-3275 3300);
FORCEPROP 3 LASTPIN (-3325 3300) SIG_NAME M_K_CPU0_SB_DQS_DN<7>
J 0
(-3315 3310);
DISPLAY 0.659574 (-3315 3310);
PAINT MONO (-3315 3310);
DISPLAY INVISIBLE (-3315 3310);
FORCEPROP 1 LASTPIN (-3325 3300) BN 7
J 0
(-3337 3308);
DISPLAY 0.489362 (-3337 3308);
PAINT GREEN (-3337 3308);
FORCEPROP 2 LAST CDS_LIB mstr_standard
J 0
(-3275 3300);
DISPLAY 0.723404 (-3275 3300);
PAINT MONO (-3275 3300);
DISPLAY INVISIBLE (-3275 3300);
FORCEPROP 1 LAST BODY_TYPE PLUMBING
J 0
(-3275 3350);
DISPLAY 0.872340 (-3275 3350);
PAINT GREEN (-3275 3350);
DISPLAY INVISIBLE (-3275 3350);
FORCEPROP 1 LAST HDL_TAP TRUE
J 0
(-2950 3175);
DISPLAY 0.872340 (-2950 3175);
DISPLAY INVISIBLE (-2950 3175);
FORCEPROP 1 LAST PATH I223
J 0
(-3277 3300);
DISPLAY 0.872340 (-3277 3300);
PAINT GREEN (-3277 3300);
DISPLAY INVISIBLE (-3277 3300);
FORCEADD TAP..1
(-3275 3000);
FORCEPROP 3 LASTPIN (-3325 3000) SIG_NAME M_K_CPU0_SB_DQS_DN<4>
J 0
(-3315 3010);
DISPLAY 0.659574 (-3315 3010);
PAINT MONO (-3315 3010);
DISPLAY INVISIBLE (-3315 3010);
FORCEPROP 1 LASTPIN (-3325 3000) BN 4
J 0
(-3337 3008);
DISPLAY 0.489362 (-3337 3008);
PAINT GREEN (-3337 3008);
FORCEPROP 2 LAST CDS_LIB mstr_standard
J 0
(-3275 3000);
DISPLAY 0.723404 (-3275 3000);
PAINT MONO (-3275 3000);
DISPLAY INVISIBLE (-3275 3000);
FORCEPROP 1 LAST BODY_TYPE PLUMBING
J 0
(-3275 3050);
DISPLAY 0.872340 (-3275 3050);
PAINT GREEN (-3275 3050);
DISPLAY INVISIBLE (-3275 3050);
FORCEPROP 1 LAST HDL_TAP TRUE
J 0
(-2950 2875);
DISPLAY 0.872340 (-2950 2875);
DISPLAY INVISIBLE (-2950 2875);
FORCEPROP 1 LAST PATH I224
J 0
(-3277 3000);
DISPLAY 0.872340 (-3277 3000);
PAINT GREEN (-3277 3000);
DISPLAY INVISIBLE (-3277 3000);
FORCEADD TAP..1
(-3275 3100);
FORCEPROP 3 LASTPIN (-3325 3100) SIG_NAME M_K_CPU0_SB_DQS_DN<5>
J 0
(-3315 3110);
DISPLAY 0.659574 (-3315 3110);
PAINT MONO (-3315 3110);
DISPLAY INVISIBLE (-3315 3110);
FORCEPROP 1 LASTPIN (-3325 3100) BN 5
J 0
(-3337 3108);
DISPLAY 0.489362 (-3337 3108);
PAINT GREEN (-3337 3108);
FORCEPROP 2 LAST CDS_LIB mstr_standard
J 0
(-3275 3100);
DISPLAY 0.723404 (-3275 3100);
PAINT MONO (-3275 3100);
DISPLAY INVISIBLE (-3275 3100);
FORCEPROP 1 LAST BODY_TYPE PLUMBING
J 0
(-3275 3150);
DISPLAY 0.872340 (-3275 3150);
PAINT GREEN (-3275 3150);
DISPLAY INVISIBLE (-3275 3150);
FORCEPROP 1 LAST HDL_TAP TRUE
J 0
(-2950 2975);
DISPLAY 0.872340 (-2950 2975);
DISPLAY INVISIBLE (-2950 2975);
FORCEPROP 1 LAST PATH I225
J 0
(-3277 3100);
DISPLAY 0.872340 (-3277 3100);
PAINT GREEN (-3277 3100);
DISPLAY INVISIBLE (-3277 3100);
FORCEADD TAP..1
(-3275 2900);
FORCEPROP 3 LASTPIN (-3325 2900) SIG_NAME M_K_CPU0_SB_DQS_DN<3>
J 0
(-3315 2910);
DISPLAY 0.659574 (-3315 2910);
PAINT MONO (-3315 2910);
DISPLAY INVISIBLE (-3315 2910);
FORCEPROP 1 LASTPIN (-3325 2900) BN 3
J 0
(-3337 2908);
DISPLAY 0.489362 (-3337 2908);
PAINT GREEN (-3337 2908);
FORCEPROP 2 LAST CDS_LIB mstr_standard
J 0
(-3275 2900);
DISPLAY 0.723404 (-3275 2900);
PAINT MONO (-3275 2900);
DISPLAY INVISIBLE (-3275 2900);
FORCEPROP 1 LAST BODY_TYPE PLUMBING
J 0
(-3275 2950);
DISPLAY 0.872340 (-3275 2950);
PAINT GREEN (-3275 2950);
DISPLAY INVISIBLE (-3275 2950);
FORCEPROP 1 LAST HDL_TAP TRUE
J 0
(-2950 2775);
DISPLAY 0.872340 (-2950 2775);
DISPLAY INVISIBLE (-2950 2775);
FORCEPROP 1 LAST PATH I226
J 0
(-3277 2900);
DISPLAY 0.872340 (-3277 2900);
PAINT GREEN (-3277 2900);
DISPLAY INVISIBLE (-3277 2900);
FORCEADD TAP..1
(-3275 2800);
FORCEPROP 3 LASTPIN (-3325 2800) SIG_NAME M_K_CPU0_SB_DQS_DN<2>
J 0
(-3315 2810);
DISPLAY 0.659574 (-3315 2810);
PAINT MONO (-3315 2810);
DISPLAY INVISIBLE (-3315 2810);
FORCEPROP 1 LASTPIN (-3325 2800) BN 2
J 0
(-3337 2808);
DISPLAY 0.489362 (-3337 2808);
PAINT GREEN (-3337 2808);
FORCEPROP 2 LAST CDS_LIB mstr_standard
J 0
(-3275 2800);
DISPLAY 0.723404 (-3275 2800);
PAINT MONO (-3275 2800);
DISPLAY INVISIBLE (-3275 2800);
FORCEPROP 1 LAST BODY_TYPE PLUMBING
J 0
(-3275 2850);
DISPLAY 0.872340 (-3275 2850);
PAINT GREEN (-3275 2850);
DISPLAY INVISIBLE (-3275 2850);
FORCEPROP 1 LAST HDL_TAP TRUE
J 0
(-2950 2675);
DISPLAY 0.872340 (-2950 2675);
DISPLAY INVISIBLE (-2950 2675);
FORCEPROP 1 LAST PATH I227
J 0
(-3277 2800);
DISPLAY 0.872340 (-3277 2800);
PAINT GREEN (-3277 2800);
DISPLAY INVISIBLE (-3277 2800);
FORCEADD TAP..1
(-3275 2700);
FORCEPROP 3 LASTPIN (-3325 2700) SIG_NAME M_K_CPU0_SB_DQS_DN<1>
J 0
(-3315 2710);
DISPLAY 0.659574 (-3315 2710);
PAINT MONO (-3315 2710);
DISPLAY INVISIBLE (-3315 2710);
FORCEPROP 1 LASTPIN (-3325 2700) BN 1
J 0
(-3337 2708);
DISPLAY 0.489362 (-3337 2708);
PAINT GREEN (-3337 2708);
FORCEPROP 2 LAST CDS_LIB mstr_standard
J 0
(-3275 2700);
DISPLAY 0.723404 (-3275 2700);
PAINT MONO (-3275 2700);
DISPLAY INVISIBLE (-3275 2700);
FORCEPROP 1 LAST BODY_TYPE PLUMBING
J 0
(-3275 2750);
DISPLAY 0.872340 (-3275 2750);
PAINT GREEN (-3275 2750);
DISPLAY INVISIBLE (-3275 2750);
FORCEPROP 1 LAST HDL_TAP TRUE
J 0
(-2950 2575);
DISPLAY 0.872340 (-2950 2575);
DISPLAY INVISIBLE (-2950 2575);
FORCEPROP 1 LAST PATH I228
J 0
(-3277 2700);
DISPLAY 0.872340 (-3277 2700);
PAINT GREEN (-3277 2700);
DISPLAY INVISIBLE (-3277 2700);
FORCEADD TAP..1
(-3275 2600);
FORCEPROP 3 LASTPIN (-3325 2600) SIG_NAME M_K_CPU0_SB_DQS_DN<0>
J 0
(-3315 2610);
DISPLAY 0.659574 (-3315 2610);
PAINT MONO (-3315 2610);
DISPLAY INVISIBLE (-3315 2610);
FORCEPROP 1 LASTPIN (-3325 2600) BN 0
J 0
(-3337 2608);
DISPLAY 0.489362 (-3337 2608);
PAINT GREEN (-3337 2608);
FORCEPROP 2 LAST CDS_LIB mstr_standard
J 0
(-3275 2600);
DISPLAY 0.723404 (-3275 2600);
PAINT MONO (-3275 2600);
DISPLAY INVISIBLE (-3275 2600);
FORCEPROP 1 LAST BODY_TYPE PLUMBING
J 0
(-3275 2650);
DISPLAY 0.872340 (-3275 2650);
PAINT GREEN (-3275 2650);
DISPLAY INVISIBLE (-3275 2650);
FORCEPROP 1 LAST HDL_TAP TRUE
J 0
(-2950 2475);
DISPLAY 0.872340 (-2950 2475);
DISPLAY INVISIBLE (-2950 2475);
FORCEPROP 1 LAST PATH I229
J 0
(-3277 2600);
DISPLAY 0.872340 (-3277 2600);
PAINT GREEN (-3277 2600);
DISPLAY INVISIBLE (-3277 2600);
FORCEADD TAP..1
R 2
(-7725 3175);
FORCEPROP 3 LASTPIN (-7675 3175) SIG_NAME M_K_CPU0_SB_CB<0>
J 0
(-7665 3185);
DISPLAY 0.659574 (-7665 3185);
PAINT MONO (-7665 3185);
DISPLAY INVISIBLE (-7665 3185);
FORCEPROP 1 LASTPIN (-7675 3175) BN 0
J 2
(-7663 3183);
DISPLAY 0.489362 (-7663 3183);
PAINT GREEN (-7663 3183);
FORCEPROP 2 LAST CDS_LIB mstr_standard
J 0
(-7725 3175);
DISPLAY 0.723404 (-7725 3175);
PAINT MONO (-7725 3175);
DISPLAY INVISIBLE (-7725 3175);
FORCEPROP 1 LAST BODY_TYPE PLUMBING
J 2
(-7725 3225);
DISPLAY 0.872340 (-7725 3225);
PAINT GREEN (-7725 3225);
DISPLAY INVISIBLE (-7725 3225);
FORCEPROP 1 LAST HDL_TAP TRUE
J 2
(-8050 3050);
DISPLAY 0.872340 (-8050 3050);
DISPLAY INVISIBLE (-8050 3050);
FORCEPROP 1 LAST PATH I23
J 2
(-7723 3175);
DISPLAY 0.872340 (-7723 3175);
PAINT GREEN (-7723 3175);
DISPLAY INVISIBLE (-7723 3175);
FORCEADD TAP..1
(-3475 3150);
FORCEPROP 3 LASTPIN (-3525 3150) SIG_NAME M_K_CPU0_SB_DQS_DP<5>
J 0
(-3515 3160);
DISPLAY 0.659574 (-3515 3160);
PAINT MONO (-3515 3160);
DISPLAY INVISIBLE (-3515 3160);
FORCEPROP 1 LASTPIN (-3525 3150) BN 5
J 0
(-3537 3158);
DISPLAY 0.489362 (-3537 3158);
PAINT GREEN (-3537 3158);
FORCEPROP 2 LAST CDS_LIB mstr_standard
J 0
(-3475 3150);
DISPLAY 0.723404 (-3475 3150);
PAINT MONO (-3475 3150);
DISPLAY INVISIBLE (-3475 3150);
FORCEPROP 1 LAST BODY_TYPE PLUMBING
J 0
(-3475 3200);
DISPLAY 0.872340 (-3475 3200);
PAINT GREEN (-3475 3200);
DISPLAY INVISIBLE (-3475 3200);
FORCEPROP 1 LAST HDL_TAP TRUE
J 0
(-3150 3025);
DISPLAY 0.872340 (-3150 3025);
DISPLAY INVISIBLE (-3150 3025);
FORCEPROP 1 LAST PATH I230
J 0
(-3477 3150);
DISPLAY 0.872340 (-3477 3150);
PAINT GREEN (-3477 3150);
DISPLAY INVISIBLE (-3477 3150);
FORCEADD TAP..1
(-3475 3050);
FORCEPROP 3 LASTPIN (-3525 3050) SIG_NAME M_K_CPU0_SB_DQS_DP<4>
J 0
(-3515 3060);
DISPLAY 0.659574 (-3515 3060);
PAINT MONO (-3515 3060);
DISPLAY INVISIBLE (-3515 3060);
FORCEPROP 1 LASTPIN (-3525 3050) BN 4
J 0
(-3537 3058);
DISPLAY 0.489362 (-3537 3058);
PAINT GREEN (-3537 3058);
FORCEPROP 2 LAST CDS_LIB mstr_standard
J 0
(-3475 3050);
DISPLAY 0.723404 (-3475 3050);
PAINT MONO (-3475 3050);
DISPLAY INVISIBLE (-3475 3050);
FORCEPROP 1 LAST BODY_TYPE PLUMBING
J 0
(-3475 3100);
DISPLAY 0.872340 (-3475 3100);
PAINT GREEN (-3475 3100);
DISPLAY INVISIBLE (-3475 3100);
FORCEPROP 1 LAST HDL_TAP TRUE
J 0
(-3150 2925);
DISPLAY 0.872340 (-3150 2925);
DISPLAY INVISIBLE (-3150 2925);
FORCEPROP 1 LAST PATH I231
J 0
(-3477 3050);
DISPLAY 0.872340 (-3477 3050);
PAINT GREEN (-3477 3050);
DISPLAY INVISIBLE (-3477 3050);
FORCEADD TAP..1
(-3475 2950);
FORCEPROP 3 LASTPIN (-3525 2950) SIG_NAME M_K_CPU0_SB_DQS_DP<3>
J 0
(-3515 2960);
DISPLAY 0.659574 (-3515 2960);
PAINT MONO (-3515 2960);
DISPLAY INVISIBLE (-3515 2960);
FORCEPROP 1 LASTPIN (-3525 2950) BN 3
J 0
(-3537 2958);
DISPLAY 0.489362 (-3537 2958);
PAINT GREEN (-3537 2958);
FORCEPROP 2 LAST CDS_LIB mstr_standard
J 0
(-3475 2950);
DISPLAY 0.723404 (-3475 2950);
PAINT MONO (-3475 2950);
DISPLAY INVISIBLE (-3475 2950);
FORCEPROP 1 LAST BODY_TYPE PLUMBING
J 0
(-3475 3000);
DISPLAY 0.872340 (-3475 3000);
PAINT GREEN (-3475 3000);
DISPLAY INVISIBLE (-3475 3000);
FORCEPROP 1 LAST HDL_TAP TRUE
J 0
(-3150 2825);
DISPLAY 0.872340 (-3150 2825);
DISPLAY INVISIBLE (-3150 2825);
FORCEPROP 1 LAST PATH I232
J 0
(-3477 2950);
DISPLAY 0.872340 (-3477 2950);
PAINT GREEN (-3477 2950);
DISPLAY INVISIBLE (-3477 2950);
FORCEADD TAP..1
(-3475 2850);
FORCEPROP 3 LASTPIN (-3525 2850) SIG_NAME M_K_CPU0_SB_DQS_DP<2>
J 0
(-3515 2860);
DISPLAY 0.659574 (-3515 2860);
PAINT MONO (-3515 2860);
DISPLAY INVISIBLE (-3515 2860);
FORCEPROP 1 LASTPIN (-3525 2850) BN 2
J 0
(-3537 2858);
DISPLAY 0.489362 (-3537 2858);
PAINT GREEN (-3537 2858);
FORCEPROP 2 LAST CDS_LIB mstr_standard
J 0
(-3475 2850);
DISPLAY 0.723404 (-3475 2850);
PAINT MONO (-3475 2850);
DISPLAY INVISIBLE (-3475 2850);
FORCEPROP 1 LAST BODY_TYPE PLUMBING
J 0
(-3475 2900);
DISPLAY 0.872340 (-3475 2900);
PAINT GREEN (-3475 2900);
DISPLAY INVISIBLE (-3475 2900);
FORCEPROP 1 LAST HDL_TAP TRUE
J 0
(-3150 2725);
DISPLAY 0.872340 (-3150 2725);
DISPLAY INVISIBLE (-3150 2725);
FORCEPROP 1 LAST PATH I233
J 0
(-3477 2850);
DISPLAY 0.872340 (-3477 2850);
PAINT GREEN (-3477 2850);
DISPLAY INVISIBLE (-3477 2850);
FORCEADD TAP..1
(-3475 2750);
FORCEPROP 3 LASTPIN (-3525 2750) SIG_NAME M_K_CPU0_SB_DQS_DP<1>
J 0
(-3515 2760);
DISPLAY 0.659574 (-3515 2760);
PAINT MONO (-3515 2760);
DISPLAY INVISIBLE (-3515 2760);
FORCEPROP 1 LASTPIN (-3525 2750) BN 1
J 0
(-3537 2758);
DISPLAY 0.489362 (-3537 2758);
PAINT GREEN (-3537 2758);
FORCEPROP 2 LAST CDS_LIB mstr_standard
J 0
(-3475 2750);
DISPLAY 0.723404 (-3475 2750);
PAINT MONO (-3475 2750);
DISPLAY INVISIBLE (-3475 2750);
FORCEPROP 1 LAST BODY_TYPE PLUMBING
J 0
(-3475 2800);
DISPLAY 0.872340 (-3475 2800);
PAINT GREEN (-3475 2800);
DISPLAY INVISIBLE (-3475 2800);
FORCEPROP 1 LAST HDL_TAP TRUE
J 0
(-3150 2625);
DISPLAY 0.872340 (-3150 2625);
DISPLAY INVISIBLE (-3150 2625);
FORCEPROP 1 LAST PATH I234
J 0
(-3477 2750);
DISPLAY 0.872340 (-3477 2750);
PAINT GREEN (-3477 2750);
DISPLAY INVISIBLE (-3477 2750);
FORCEADD TAP..1
(-3475 2650);
FORCEPROP 3 LASTPIN (-3525 2650) SIG_NAME M_K_CPU0_SB_DQS_DP<0>
J 0
(-3515 2660);
DISPLAY 0.659574 (-3515 2660);
PAINT MONO (-3515 2660);
DISPLAY INVISIBLE (-3515 2660);
FORCEPROP 1 LASTPIN (-3525 2650) BN 0
J 0
(-3537 2658);
DISPLAY 0.489362 (-3537 2658);
PAINT GREEN (-3537 2658);
FORCEPROP 2 LAST CDS_LIB mstr_standard
J 0
(-3475 2650);
DISPLAY 0.723404 (-3475 2650);
PAINT MONO (-3475 2650);
DISPLAY INVISIBLE (-3475 2650);
FORCEPROP 1 LAST BODY_TYPE PLUMBING
J 0
(-3475 2700);
DISPLAY 0.872340 (-3475 2700);
PAINT GREEN (-3475 2700);
DISPLAY INVISIBLE (-3475 2700);
FORCEPROP 1 LAST HDL_TAP TRUE
J 0
(-3150 2525);
DISPLAY 0.872340 (-3150 2525);
DISPLAY INVISIBLE (-3150 2525);
FORCEPROP 1 LAST PATH I235
J 0
(-3477 2650);
DISPLAY 0.872340 (-3477 2650);
PAINT GREEN (-3477 2650);
DISPLAY INVISIBLE (-3477 2650);
FORCEADD SCONN288_DDR506112002KQ..2
(-4425 3600);
FORCEPROP 1 LAST LOCATION J20
J 0
(-5025 4925);
DISPLAY 0.468085 (-5025 4925);
PAINT SKYBLUE (-5025 4925);
FORCEPROP 0 LAST $SEC 2
J 0
(-4875 5075);
DISPLAY 0.680851 (-4875 5075);
PAINT MONO (-4875 5075);
DISPLAY INVISIBLE (-4875 5075);
FORCEPROP 0 LAST CDS_SEC 2
J 0
(-4875 5075);
DISPLAY 1.021277 (-4875 5075);
DISPLAY INVISIBLE (-4875 5075);
FORCEPROP 0 LASTPIN (-3675 3650) $PN 12
J 0
(-3665 3660);
DISPLAY 0.680851 (-3665 3660);
PAINT MONO (-3665 3660);
FORCEPROP 0 LASTPIN (-3675 3700) $PN 11
J 0
(-3665 3710);
DISPLAY 0.680851 (-3665 3710);
PAINT MONO (-3665 3710);
FORCEPROP 0 LASTPIN (-3675 2600) $PN 105
J 0
(-3665 2610);
DISPLAY 0.680851 (-3665 2610);
PAINT MONO (-3665 2610);
FORCEPROP 0 LASTPIN (-3675 2650) $PN 104
J 0
(-3665 2660);
DISPLAY 0.680851 (-3665 2660);
PAINT MONO (-3665 2660);
FORCEPROP 0 LASTPIN (-3675 3750) $PN 23
J 0
(-3665 3760);
DISPLAY 0.680851 (-3665 3760);
PAINT MONO (-3665 3760);
FORCEPROP 0 LASTPIN (-3675 3800) $PN 22
J 0
(-3665 3810);
DISPLAY 0.680851 (-3665 3810);
PAINT MONO (-3665 3810);
FORCEPROP 0 LASTPIN (-3675 2700) $PN 116
J 0
(-3665 2710);
DISPLAY 0.680851 (-3665 2710);
PAINT MONO (-3665 2710);
FORCEPROP 0 LASTPIN (-3675 2750) $PN 115
J 0
(-3665 2760);
DISPLAY 0.680851 (-3665 2760);
PAINT MONO (-3665 2760);
FORCEPROP 0 LASTPIN (-3675 3850) $PN 34
J 0
(-3665 3860);
DISPLAY 0.680851 (-3665 3860);
PAINT MONO (-3665 3860);
FORCEPROP 0 LASTPIN (-3675 3900) $PN 33
J 0
(-3665 3910);
DISPLAY 0.680851 (-3665 3910);
PAINT MONO (-3665 3910);
FORCEPROP 0 LASTPIN (-3675 2800) $PN 127
J 0
(-3665 2810);
DISPLAY 0.680851 (-3665 2810);
PAINT MONO (-3665 2810);
FORCEPROP 0 LASTPIN (-3675 2850) $PN 126
J 0
(-3665 2860);
DISPLAY 0.680851 (-3665 2860);
PAINT MONO (-3665 2860);
FORCEPROP 0 LASTPIN (-3675 3950) $PN 45
J 0
(-3665 3960);
DISPLAY 0.680851 (-3665 3960);
PAINT MONO (-3665 3960);
FORCEPROP 0 LASTPIN (-3675 4000) $PN 44
J 0
(-3665 4010);
DISPLAY 0.680851 (-3665 4010);
PAINT MONO (-3665 4010);
FORCEPROP 0 LASTPIN (-3675 2900) $PN 138
J 0
(-3665 2910);
DISPLAY 0.680851 (-3665 2910);
PAINT MONO (-3665 2910);
FORCEPROP 0 LASTPIN (-3675 2950) $PN 137
J 0
(-3665 2960);
DISPLAY 0.680851 (-3665 2960);
PAINT MONO (-3665 2960);
FORCEPROP 0 LASTPIN (-3675 4050) $PN 56
J 0
(-3665 4060);
DISPLAY 0.680851 (-3665 4060);
PAINT MONO (-3665 4060);
FORCEPROP 0 LASTPIN (-3675 4100) $PN 55
J 0
(-3665 4110);
DISPLAY 0.680851 (-3665 4110);
PAINT MONO (-3665 4110);
FORCEPROP 0 LASTPIN (-3675 3000) $PN 238
J 0
(-3665 3010);
DISPLAY 0.680851 (-3665 3010);
PAINT MONO (-3665 3010);
FORCEPROP 0 LASTPIN (-3675 3050) $PN 239
J 0
(-3665 3060);
DISPLAY 0.680851 (-3665 3060);
PAINT MONO (-3665 3060);
FORCEPROP 0 LASTPIN (-3675 4150) $PN 156
J 0
(-3665 4160);
DISPLAY 0.680851 (-3665 4160);
PAINT MONO (-3665 4160);
FORCEPROP 0 LASTPIN (-3675 4200) $PN 157
J 0
(-3665 4210);
DISPLAY 0.680851 (-3665 4210);
PAINT MONO (-3665 4210);
FORCEPROP 0 LASTPIN (-3675 3100) $PN 249
J 0
(-3665 3110);
DISPLAY 0.680851 (-3665 3110);
PAINT MONO (-3665 3110);
FORCEPROP 0 LASTPIN (-3675 3150) $PN 250
J 0
(-3665 3160);
DISPLAY 0.680851 (-3665 3160);
PAINT MONO (-3665 3160);
FORCEPROP 0 LASTPIN (-3675 4250) $PN 167
J 0
(-3665 4260);
DISPLAY 0.680851 (-3665 4260);
PAINT MONO (-3665 4260);
FORCEPROP 0 LASTPIN (-3675 4300) $PN 168
J 0
(-3665 4310);
DISPLAY 0.680851 (-3665 4310);
PAINT MONO (-3665 4310);
FORCEPROP 0 LASTPIN (-3675 3200) $PN 260
J 0
(-3665 3210);
DISPLAY 0.680851 (-3665 3210);
PAINT MONO (-3665 3210);
FORCEPROP 0 LASTPIN (-3675 3250) $PN 261
J 0
(-3665 3260);
DISPLAY 0.680851 (-3665 3260);
PAINT MONO (-3665 3260);
FORCEPROP 0 LASTPIN (-3675 4350) $PN 178
J 0
(-3665 4360);
DISPLAY 0.680851 (-3665 4360);
PAINT MONO (-3665 4360);
FORCEPROP 0 LASTPIN (-3675 4400) $PN 179
J 0
(-3665 4410);
DISPLAY 0.680851 (-3665 4410);
PAINT MONO (-3665 4410);
FORCEPROP 0 LASTPIN (-3675 3300) $PN 271
J 0
(-3665 3310);
DISPLAY 0.680851 (-3665 3310);
PAINT MONO (-3665 3310);
FORCEPROP 0 LASTPIN (-3675 3350) $PN 272
J 0
(-3665 3360);
DISPLAY 0.680851 (-3665 3360);
PAINT MONO (-3665 3360);
FORCEPROP 0 LASTPIN (-3675 4450) $PN 189
J 0
(-3665 4460);
DISPLAY 0.680851 (-3665 4460);
PAINT MONO (-3665 4460);
FORCEPROP 0 LASTPIN (-3675 4500) $PN 190
J 0
(-3665 4510);
DISPLAY 0.680851 (-3665 4510);
PAINT MONO (-3665 4510);
FORCEPROP 0 LASTPIN (-3675 3400) $PN 282
J 0
(-3665 3410);
DISPLAY 0.680851 (-3665 3410);
PAINT MONO (-3665 3410);
FORCEPROP 0 LASTPIN (-3675 3450) $PN 283
J 0
(-3665 3460);
DISPLAY 0.680851 (-3665 3460);
PAINT MONO (-3665 3460);
FORCEPROP 0 LASTPIN (-3675 4550) $PN 200
J 0
(-3665 4560);
DISPLAY 0.680851 (-3665 4560);
PAINT MONO (-3665 4560);
FORCEPROP 0 LASTPIN (-3675 4600) $PN 201
J 0
(-3665 4610);
DISPLAY 0.680851 (-3665 4610);
PAINT MONO (-3665 4610);
FORCEPROP 0 LASTPIN (-3675 3500) $PN 94
J 0
(-3665 3510);
DISPLAY 0.680851 (-3665 3510);
PAINT MONO (-3665 3510);
FORCEPROP 0 LASTPIN (-3675 3550) $PN 93
J 0
(-3665 3560);
DISPLAY 0.680851 (-3665 3560);
PAINT MONO (-3665 3560);
FORCEPROP 2 LAST PART_TYPE SMLF
J 0
(-4875 5025);
DISPLAY 1.021277 (-4875 5025);
FORCEPROP 1 LAST MATERIAL IO
J 0
(-5025 4775);
DISPLAY 0.468085 (-5025 4775);
PAINT SKYBLUE (-5025 4775);
FORCEPROP 2 LAST VALUE SCONN288_DDR506112002KQ
J 0
(-4875 4975);
DISPLAY 0.489362 (-4875 4975);
PAINT SKYBLUE (-4875 4975);
FORCEPROP 1 LAST CDS_LMAN_SYM_OUTLINE -600,1150,600,-1150
J 0
(-4425 3600);
DISPLAY 0.468085 (-4425 3600);
PAINT GREEN (-4425 3600);
DISPLAY INVISIBLE (-4425 3600);
FORCEPROP 1 LAST NEEDS_NO_SIZE TRUE
J 0
(-4425 3600);
DISPLAY 0.723404 (-4425 3600);
PAINT GREEN (-4425 3600);
DISPLAY INVISIBLE (-4425 3600);
FORCEPROP 2 LAST CDS_LIB pure_quanta
J 0
(-4425 3600);
DISPLAY INVISIBLE (-4425 3600);
FORCEPROP 1 LAST PATH I236
J 0
(-4425 3600);
DISPLAY 0.723404 (-4425 3600);
PAINT GREEN (-4425 3600);
DISPLAY INVISIBLE (-4425 3600);
FORCEPROP 1 LAST PART_NUMBER DFHST8FS479
J 0
(-5025 4850);
DISPLAY 0.468085 (-5025 4850);
PAINT SKYBLUE (-5025 4850);
DISPLAY INVISIBLE (-5025 4850);
FORCEADD GND..1
(-2825 5650);
FORCEPROP 3 LASTPIN (-2825 5700) SIG_NAME GND\g
J 0
(-2815 5710);
DISPLAY 0.659574 (-2815 5710);
PAINT MONO (-2815 5710);
DISPLAY INVISIBLE (-2815 5710);
FORCEPROP 2 LAST CDS_LIB pure_quanta_power
J 0
(-2825 5650);
DISPLAY INVISIBLE (-2825 5650);
FORCEPROP 2 LAST BOM_COST MEM
J 0
(-2800 5775);
DISPLAY 0.659574 (-2800 5775);
DISPLAY INVISIBLE (-2800 5775);
FORCEPROP 1 LAST SIZE 1B
J 0
(-2750 5600);
DISPLAY 0.723404 (-2750 5600);
PAINT GREEN (-2750 5600);
DISPLAY INVISIBLE (-2750 5600);
FORCEPROP 2 LAST ROOM MEM_EFGH_DECOUPLING_CAPS
J 0
(-2800 5725);
DISPLAY 0.659574 (-2800 5725);
PAINT RED (-2800 5725);
DISPLAY INVISIBLE (-2800 5725);
FORCEPROP 1 LAST HDL_POWER GND
J 0
(-2825 5800);
DISPLAY 0.723404 (-2825 5800);
PAINT GREEN (-2825 5800);
DISPLAY INVISIBLE (-2825 5800);
FORCEPROP 1 LAST PATH I237
J 0
(-2750 5650);
DISPLAY 0.872340 (-2750 5650);
PAINT AQUA (-2750 5650);
DISPLAY INVISIBLE (-2750 5650);
FORCEADD Q_CAP..1
R 2
(-2825 6000);
FORCEPROP 1 LAST LOCATION C167
J 2
(-2875 6100);
DISPLAY 0.489362 (-2875 6100);
PAINT SKYBLUE (-2875 6100);
FORCEPROP 0 LAST $SEC 1
J 0
(-2875 6150);
DISPLAY 0.680851 (-2875 6150);
PAINT MONO (-2875 6150);
DISPLAY INVISIBLE (-2875 6150);
FORCEPROP 0 LAST CDS_SEC 1
J 0
(-2875 6150);
DISPLAY 0.680851 (-2875 6150);
DISPLAY INVISIBLE (-2875 6150);
FORCEPROP 1 LASTPIN (-2825 6100) $PN 1
J 2
(-2835 6080);
DISPLAY 0.489362 (-2835 6080);
PAINT MONO (-2835 6080);
FORCEPROP 1 LASTPIN (-2825 5900) $PN 2
J 2
(-2835 5880);
DISPLAY 0.489362 (-2835 5880);
PAINT MONO (-2835 5880);
FORCEPROP 1 LAST PACK_TYPE C0805
J 2
(-2875 5800);
DISPLAY 0.489362 (-2875 5800);
PAINT SKYBLUE (-2875 5800);
FORCEPROP 1 LAST VOLTAGE 25V
J 2
(-2875 6000);
DISPLAY 0.489362 (-2875 6000);
PAINT SKYBLUE (-2875 6000);
FORCEPROP 1 LAST VALUE 10UF
J 2
(-2875 6050);
DISPLAY 0.489362 (-2875 6050);
PAINT SKYBLUE (-2875 6050);
FORCEPROP 1 LAST TOLERANCE 10%
J 2
(-2875 5950);
DISPLAY 0.489362 (-2875 5950);
PAINT SKYBLUE (-2875 5950);
FORCEPROP 1 LAST MATERIAL X6S
J 2
(-2875 5900);
DISPLAY 0.489362 (-2875 5900);
PAINT SKYBLUE (-2875 5900);
FORCEPROP 2 LAST CDS_LIB pure_quanta
J 0
(-2825 6000);
DISPLAY INVISIBLE (-2825 6000);
FORCEPROP 0 LAST BOM_COST MEM
J 2
(-2880 6145);
DISPLAY 0.595745 (-2880 6145);
PAINT MONO (-2880 6145);
DISPLAY INVISIBLE (-2880 6145);
FORCEPROP 2 LAST ROOM 
J 2
(-2880 6145);
DISPLAY 0.595745 (-2880 6145);
PAINT RED (-2880 6145);
DISPLAY INVISIBLE (-2880 6145);
FORCEPROP 1 LAST PATH I238
J 2
(-2875 6150);
DISPLAY 0.978723 (-2875 6150);
PAINT WHITE (-2875 6150);
DISPLAY INVISIBLE (-2875 6150);
FORCEPROP 1 LAST PART_NUMBER CH6104KEA00
J 2
(-2875 5850);
DISPLAY 0.489362 (-2875 5850);
PAINT SKYBLUE (-2875 5850);
DISPLAY INVISIBLE (-2875 5850);
FORCEADD Q_CAP..1
R 2
(-2250 6000);
FORCEPROP 1 LAST LOCATION C169
J 2
(-2300 6100);
DISPLAY 0.489362 (-2300 6100);
PAINT SKYBLUE (-2300 6100);
FORCEPROP 0 LAST $SEC 1
J 0
(-2300 6150);
DISPLAY 0.680851 (-2300 6150);
PAINT MONO (-2300 6150);
DISPLAY INVISIBLE (-2300 6150);
FORCEPROP 0 LAST CDS_SEC 1
J 0
(-2300 6150);
DISPLAY 0.680851 (-2300 6150);
DISPLAY INVISIBLE (-2300 6150);
FORCEPROP 1 LASTPIN (-2250 6100) $PN 1
J 2
(-2260 6080);
DISPLAY 0.489362 (-2260 6080);
PAINT MONO (-2260 6080);
FORCEPROP 1 LASTPIN (-2250 5900) $PN 2
J 2
(-2260 5880);
DISPLAY 0.489362 (-2260 5880);
PAINT MONO (-2260 5880);
FORCEPROP 1 LAST PACK_TYPE C0805
J 2
(-2300 5800);
DISPLAY 0.489362 (-2300 5800);
PAINT SKYBLUE (-2300 5800);
FORCEPROP 1 LAST VOLTAGE 25V
J 2
(-2300 6000);
DISPLAY 0.489362 (-2300 6000);
PAINT SKYBLUE (-2300 6000);
FORCEPROP 1 LAST VALUE 10UF
J 2
(-2300 6050);
DISPLAY 0.489362 (-2300 6050);
PAINT SKYBLUE (-2300 6050);
FORCEPROP 1 LAST TOLERANCE 10%
J 2
(-2300 5950);
DISPLAY 0.489362 (-2300 5950);
PAINT SKYBLUE (-2300 5950);
FORCEPROP 1 LAST MATERIAL X6S
J 2
(-2300 5900);
DISPLAY 0.489362 (-2300 5900);
PAINT SKYBLUE (-2300 5900);
FORCEPROP 2 LAST CDS_LIB pure_quanta
J 0
(-2250 6000);
DISPLAY INVISIBLE (-2250 6000);
FORCEPROP 0 LAST BOM_COST MEM
J 2
(-2305 6145);
DISPLAY 0.595745 (-2305 6145);
PAINT MONO (-2305 6145);
DISPLAY INVISIBLE (-2305 6145);
FORCEPROP 2 LAST ROOM 
J 2
(-2305 6145);
DISPLAY 0.595745 (-2305 6145);
PAINT RED (-2305 6145);
DISPLAY INVISIBLE (-2305 6145);
FORCEPROP 1 LAST PATH I239
J 2
(-2300 6150);
DISPLAY 0.978723 (-2300 6150);
PAINT WHITE (-2300 6150);
DISPLAY INVISIBLE (-2300 6150);
FORCEPROP 1 LAST PART_NUMBER CH6104KEA00
J 2
(-2300 5850);
DISPLAY 0.489362 (-2300 5850);
PAINT SKYBLUE (-2300 5850);
DISPLAY INVISIBLE (-2300 5850);
FORCEADD TAP..1
R 2
(-7725 3225);
FORCEPROP 3 LASTPIN (-7675 3225) SIG_NAME M_K_CPU0_SB_CB<1>
J 0
(-7665 3235);
DISPLAY 0.659574 (-7665 3235);
PAINT MONO (-7665 3235);
DISPLAY INVISIBLE (-7665 3235);
FORCEPROP 1 LASTPIN (-7675 3225) BN 1
J 2
(-7663 3233);
DISPLAY 0.489362 (-7663 3233);
PAINT GREEN (-7663 3233);
FORCEPROP 2 LAST CDS_LIB mstr_standard
J 0
(-7725 3225);
DISPLAY 0.723404 (-7725 3225);
PAINT MONO (-7725 3225);
DISPLAY INVISIBLE (-7725 3225);
FORCEPROP 1 LAST BODY_TYPE PLUMBING
J 2
(-7725 3275);
DISPLAY 0.872340 (-7725 3275);
PAINT GREEN (-7725 3275);
DISPLAY INVISIBLE (-7725 3275);
FORCEPROP 1 LAST HDL_TAP TRUE
J 2
(-8050 3100);
DISPLAY 0.872340 (-8050 3100);
DISPLAY INVISIBLE (-8050 3100);
FORCEPROP 1 LAST PATH I24
J 2
(-7723 3225);
DISPLAY 0.872340 (-7723 3225);
PAINT GREEN (-7723 3225);
DISPLAY INVISIBLE (-7723 3225);
FORCEADD UNIVERSAL_POWER..1
(-2825 6325);
FORCEPROP 3 LASTPIN (-2825 6275) SIG_NAME P12V_MEM_CPU0\g
J 0
(-2815 6285);
DISPLAY 0.659574 (-2815 6285);
PAINT MONO (-2815 6285);
DISPLAY INVISIBLE (-2815 6285);
FORCEPROP 1 LAST HDL_POWER P12V_MEM_CPU0
J 1
(-2850 6375);
DISPLAY 0.489362 (-2850 6375);
PAINT GREEN (-2850 6375);
FORCEPROP 2 LAST BOM_COST VR_SYSTEM
J 0
(-2825 6425);
DISPLAY 0.617021 (-2825 6425);
PAINT PURPLE (-2825 6425);
DISPLAY INVISIBLE (-2825 6425);
FORCEPROP 2 LAST CDS_LIB pure_quanta_power
J 0
(-2825 6325);
DISPLAY INVISIBLE (-2825 6325);
FORCEPROP 1 LAST PATH I240
J 0
(-2775 6350);
DISPLAY 0.872340 (-2775 6350);
PAINT AQUA (-2775 6350);
DISPLAY INVISIBLE (-2775 6350);
FORCEADD OFFPAGE..1
(-8425 2600);
FORCEPROP 2 LAST $XR5 97 
J 0
(-9127 2600);
DISPLAY 0.638298 (-9127 2600);
PAINT MONO (-9127 2600);
FORCEPROP 2 LAST $XR4 95 
J 0
(-9037 2600);
DISPLAY 0.638298 (-9037 2600);
PAINT MONO (-9037 2600);
FORCEPROP 2 LAST $XR3 94 
J 0
(-8947 2600);
DISPLAY 0.638298 (-8947 2600);
PAINT MONO (-8947 2600);
FORCEPROP 2 LAST $XR2 93 
J 0
(-8857 2600);
DISPLAY 0.638298 (-8857 2600);
PAINT MONO (-8857 2600);
FORCEPROP 2 LAST $XR1 92 
J 0
(-8767 2600);
DISPLAY 0.638298 (-8767 2600);
PAINT MONO (-8767 2600);
FORCEPROP 2 LAST $XR0 159 
J 0
(-8677 2600);
DISPLAY 0.638298 (-8677 2600);
PAINT MONO (-8677 2600);
FORCEPROP 2 LAST CDS_LIB mstr_standard
J 0
(-8425 2600);
DISPLAY 0.808511 (-8425 2600);
DISPLAY INVISIBLE (-8425 2600);
FORCEPROP 1 LAST OFFPAGE TRUE
J 0
(-8100 2475);
DISPLAY 0.872340 (-8100 2475);
PAINT GREEN (-8100 2475);
DISPLAY INVISIBLE (-8100 2475);
FORCEPROP 1 LAST COMMENT_BODY TRUE
J 0
(-8300 2500);
DISPLAY 0.872340 (-8300 2500);
PAINT GREEN (-8300 2500);
DISPLAY INVISIBLE (-8300 2500);
FORCEPROP 2 LAST PATH I241
J 0
(-8700 2650);
DISPLAY 0.680851 (-8700 2650);
DISPLAY INVISIBLE (-8700 2650);
FORCEADD Q_RES..1
(-7775 2600);
FORCEPROP 1 LAST LOCATION R1578
J 0
(-7825 2625);
DISPLAY 0.510638 (-7825 2625);
PAINT SKYBLUE (-7825 2625);
FORCEPROP 0 LAST $SEC 1
J 0
(-7825 2700);
DISPLAY 0.680851 (-7825 2700);
PAINT MONO (-7825 2700);
DISPLAY INVISIBLE (-7825 2700);
FORCEPROP 0 LAST CDS_SEC 1
J 0
(-7825 2700);
DISPLAY 0.680851 (-7825 2700);
DISPLAY INVISIBLE (-7825 2700);
FORCEPROP 1 LASTPIN (-7875 2600) $PN 1
J 0
(-7863 2612);
DISPLAY 0.787234 (-7863 2612);
PAINT MONO (-7863 2612);
FORCEPROP 1 LASTPIN (-7675 2600) $PN 2
J 0
(-7713 2612);
DISPLAY 0.787234 (-7713 2612);
PAINT MONO (-7713 2612);
FORCEPROP 1 LAST VALUE 49.9
J 2
(-7625 2650);
DISPLAY 0.510638 (-7625 2650);
PAINT SKYBLUE (-7625 2650);
FORCEPROP 2 LAST CDS_LIB pure_quanta
J 0
(-7775 2600);
DISPLAY INVISIBLE (-7775 2600);
FORCEPROP 1 LAST TOLERANCE 1%
J 0
(-7775 2500);
DISPLAY 0.978723 (-7775 2500);
DISPLAY INVISIBLE (-7775 2500);
FORCEPROP 1 LAST WATTAGE 1/16W
J 2
(-7800 2450);
DISPLAY 0.978723 (-7800 2450);
DISPLAY INVISIBLE (-7800 2450);
FORCEPROP 1 LAST PACK_TYPE 0402LF
J 0
(-7525 2450);
DISPLAY 0.978723 (-7525 2450);
DISPLAY INVISIBLE (-7525 2450);
FORCEPROP 1 LAST MATERIAL CHIP
J 0
(-7775 2450);
DISPLAY 0.978723 (-7775 2450);
DISPLAY INVISIBLE (-7775 2450);
FORCEPROP 1 LAST PATH I242
J 0
(-7825 2750);
DISPLAY 0.978723 (-7825 2750);
PAINT WHITE (-7825 2750);
DISPLAY INVISIBLE (-7825 2750);
FORCEPROP 1 LAST PART_NUMBER CS04992FB07
J 0
(-7825 2700);
DISPLAY 0.978723 (-7825 2700);
DISPLAY INVISIBLE (-7825 2700);
FORCEADD Q_RES..1
(-8175 2825);
FORCEPROP 1 LAST LOCATION R1685
J 0
(-8375 2825);
DISPLAY 0.638298 (-8375 2825);
FORCEPROP 0 LAST $SEC 1
J 0
(-8325 2875);
DISPLAY 0.680851 (-8325 2875);
PAINT MONO (-8325 2875);
DISPLAY INVISIBLE (-8325 2875);
FORCEPROP 0 LAST CDS_SEC 1
J 0
(-8325 2875);
DISPLAY 0.680851 (-8325 2875);
DISPLAY INVISIBLE (-8325 2875);
FORCEPROP 1 LASTPIN (-8275 2825) $PN 1
J 0
(-8263 2837);
DISPLAY 0.787234 (-8263 2837);
PAINT MONO (-8263 2837);
FORCEPROP 1 LASTPIN (-8075 2825) $PN 2
J 0
(-8113 2837);
DISPLAY 0.787234 (-8113 2837);
PAINT MONO (-8113 2837);
FORCEPROP 1 LAST PACK_TYPE 0402LF
J 0
(-8125 2800);
DISPLAY 0.404255 (-8125 2800);
FORCEPROP 1 LAST VALUE 10
J 2
(-8025 2825);
DISPLAY 0.404255 (-8025 2825);
FORCEPROP 1 LAST MATERIAL CHIP
J 0
(-8275 2800);
DISPLAY 0.404255 (-8275 2800);
FORCEPROP 2 LAST CDS_LIB pure_quanta
J 0
(-8175 2825);
DISPLAY INVISIBLE (-8175 2825);
FORCEPROP 1 LAST TOLERANCE 1%
J 0
(-8175 2725);
DISPLAY 0.978723 (-8175 2725);
DISPLAY INVISIBLE (-8175 2725);
FORCEPROP 1 LAST WATTAGE 1/16W
J 2
(-8200 2675);
DISPLAY 0.978723 (-8200 2675);
DISPLAY INVISIBLE (-8200 2675);
FORCEPROP 1 LAST PATH I243
J 0
(-8225 2975);
DISPLAY 0.978723 (-8225 2975);
PAINT WHITE (-8225 2975);
DISPLAY INVISIBLE (-8225 2975);
FORCEPROP 1 LAST PART_NUMBER CS01002FB07
J 0
(-8225 2925);
DISPLAY 0.978723 (-8225 2925);
DISPLAY INVISIBLE (-8225 2925);
FORCEADD OFFPAGE..6
(-8850 2700);
FORCEPROP 2 LAST $XR5 159 
J 0
(-9339 2664);
DISPLAY 0.638298 (-9339 2664);
PAINT MONO (-9339 2664);
FORCEPROP 2 LAST $XR4 97 
J 0
(-9219 2664);
DISPLAY 0.638298 (-9219 2664);
PAINT MONO (-9219 2664);
FORCEPROP 2 LAST $XR3 95 
J 0
(-9129 2664);
DISPLAY 0.638298 (-9129 2664);
PAINT MONO (-9129 2664);
FORCEPROP 2 LAST $XR2 94 
J 0
(-9309 2700);
DISPLAY 0.638298 (-9309 2700);
PAINT MONO (-9309 2700);
FORCEPROP 2 LAST $XR1 93 
J 0
(-9219 2700);
DISPLAY 0.638298 (-9219 2700);
PAINT MONO (-9219 2700);
FORCEPROP 2 LAST $XR0 92 
J 0
(-9129 2700);
DISPLAY 0.638298 (-9129 2700);
PAINT MONO (-9129 2700);
FORCEPROP 2 LAST CDS_LIB mstr_standard
J 0
(-8850 2700);
DISPLAY 0.808511 (-8850 2700);
DISPLAY INVISIBLE (-8850 2700);
FORCEPROP 1 LAST OFFPAGE TRUE
J 0
(-8525 2575);
DISPLAY 0.872340 (-8525 2575);
PAINT GREEN (-8525 2575);
DISPLAY INVISIBLE (-8525 2575);
FORCEPROP 1 LAST COMMENT_BODY TRUE
J 0
(-8750 2625);
DISPLAY 0.872340 (-8750 2625);
PAINT GREEN (-8750 2625);
DISPLAY INVISIBLE (-8750 2625);
FORCEPROP 2 LAST PATH I244
J 0
(-9075 2750);
DISPLAY 0.680851 (-9075 2750);
DISPLAY INVISIBLE (-9075 2750);
FORCEADD TAP..1
R 2
(-7725 3275);
FORCEPROP 3 LASTPIN (-7675 3275) SIG_NAME M_K_CPU0_SB_CB<2>
J 0
(-7665 3285);
DISPLAY 0.659574 (-7665 3285);
PAINT MONO (-7665 3285);
DISPLAY INVISIBLE (-7665 3285);
FORCEPROP 1 LASTPIN (-7675 3275) BN 2
J 2
(-7663 3283);
DISPLAY 0.489362 (-7663 3283);
PAINT GREEN (-7663 3283);
FORCEPROP 2 LAST CDS_LIB mstr_standard
J 0
(-7725 3275);
DISPLAY 0.723404 (-7725 3275);
PAINT MONO (-7725 3275);
DISPLAY INVISIBLE (-7725 3275);
FORCEPROP 1 LAST BODY_TYPE PLUMBING
J 2
(-7725 3325);
DISPLAY 0.872340 (-7725 3325);
PAINT GREEN (-7725 3325);
DISPLAY INVISIBLE (-7725 3325);
FORCEPROP 1 LAST HDL_TAP TRUE
J 2
(-8050 3150);
DISPLAY 0.872340 (-8050 3150);
DISPLAY INVISIBLE (-8050 3150);
FORCEPROP 1 LAST PATH I25
J 2
(-7723 3275);
DISPLAY 0.872340 (-7723 3275);
PAINT GREEN (-7723 3275);
DISPLAY INVISIBLE (-7723 3275);
FORCEADD TAP..1
R 2
(-7725 3375);
FORCEPROP 3 LASTPIN (-7675 3375) SIG_NAME M_K_CPU0_SB_CB<4>
J 0
(-7665 3385);
DISPLAY 0.659574 (-7665 3385);
PAINT MONO (-7665 3385);
DISPLAY INVISIBLE (-7665 3385);
FORCEPROP 1 LASTPIN (-7675 3375) BN 4
J 2
(-7663 3383);
DISPLAY 0.489362 (-7663 3383);
PAINT GREEN (-7663 3383);
FORCEPROP 2 LAST CDS_LIB mstr_standard
J 0
(-7725 3375);
DISPLAY 0.723404 (-7725 3375);
PAINT MONO (-7725 3375);
DISPLAY INVISIBLE (-7725 3375);
FORCEPROP 1 LAST BODY_TYPE PLUMBING
J 2
(-7725 3425);
DISPLAY 0.872340 (-7725 3425);
PAINT GREEN (-7725 3425);
DISPLAY INVISIBLE (-7725 3425);
FORCEPROP 1 LAST HDL_TAP TRUE
J 2
(-8050 3250);
DISPLAY 0.872340 (-8050 3250);
DISPLAY INVISIBLE (-8050 3250);
FORCEPROP 1 LAST PATH I26
J 2
(-7723 3375);
DISPLAY 0.872340 (-7723 3375);
PAINT GREEN (-7723 3375);
DISPLAY INVISIBLE (-7723 3375);
FORCEADD TAP..1
R 2
(-7725 3325);
FORCEPROP 3 LASTPIN (-7675 3325) SIG_NAME M_K_CPU0_SB_CB<3>
J 0
(-7665 3335);
DISPLAY 0.659574 (-7665 3335);
PAINT MONO (-7665 3335);
DISPLAY INVISIBLE (-7665 3335);
FORCEPROP 1 LASTPIN (-7675 3325) BN 3
J 2
(-7663 3333);
DISPLAY 0.489362 (-7663 3333);
PAINT GREEN (-7663 3333);
FORCEPROP 2 LAST CDS_LIB mstr_standard
J 0
(-7725 3325);
DISPLAY 0.723404 (-7725 3325);
PAINT MONO (-7725 3325);
DISPLAY INVISIBLE (-7725 3325);
FORCEPROP 1 LAST BODY_TYPE PLUMBING
J 2
(-7725 3375);
DISPLAY 0.872340 (-7725 3375);
PAINT GREEN (-7725 3375);
DISPLAY INVISIBLE (-7725 3375);
FORCEPROP 1 LAST HDL_TAP TRUE
J 2
(-8050 3200);
DISPLAY 0.872340 (-8050 3200);
DISPLAY INVISIBLE (-8050 3200);
FORCEPROP 1 LAST PATH I27
J 2
(-7723 3325);
DISPLAY 0.872340 (-7723 3325);
PAINT GREEN (-7723 3325);
DISPLAY INVISIBLE (-7723 3325);
FORCEADD TAP..1
R 2
(-7725 3425);
FORCEPROP 3 LASTPIN (-7675 3425) SIG_NAME M_K_CPU0_SB_CB<5>
J 0
(-7665 3435);
DISPLAY 0.659574 (-7665 3435);
PAINT MONO (-7665 3435);
DISPLAY INVISIBLE (-7665 3435);
FORCEPROP 1 LASTPIN (-7675 3425) BN 5
J 2
(-7663 3433);
DISPLAY 0.489362 (-7663 3433);
PAINT GREEN (-7663 3433);
FORCEPROP 2 LAST CDS_LIB mstr_standard
J 0
(-7725 3425);
DISPLAY 0.723404 (-7725 3425);
PAINT MONO (-7725 3425);
DISPLAY INVISIBLE (-7725 3425);
FORCEPROP 1 LAST BODY_TYPE PLUMBING
J 2
(-7725 3475);
DISPLAY 0.872340 (-7725 3475);
PAINT GREEN (-7725 3475);
DISPLAY INVISIBLE (-7725 3475);
FORCEPROP 1 LAST HDL_TAP TRUE
J 2
(-8050 3300);
DISPLAY 0.872340 (-8050 3300);
DISPLAY INVISIBLE (-8050 3300);
FORCEPROP 1 LAST PATH I28
J 2
(-7723 3425);
DISPLAY 0.872340 (-7723 3425);
PAINT GREEN (-7723 3425);
DISPLAY INVISIBLE (-7723 3425);
FORCEADD TAP..1
R 2
(-7725 3475);
FORCEPROP 3 LASTPIN (-7675 3475) SIG_NAME M_K_CPU0_SB_CB<6>
J 0
(-7665 3485);
DISPLAY 0.659574 (-7665 3485);
PAINT MONO (-7665 3485);
DISPLAY INVISIBLE (-7665 3485);
FORCEPROP 1 LASTPIN (-7675 3475) BN 6
J 2
(-7663 3483);
DISPLAY 0.489362 (-7663 3483);
PAINT GREEN (-7663 3483);
FORCEPROP 2 LAST CDS_LIB mstr_standard
J 0
(-7725 3475);
DISPLAY 0.723404 (-7725 3475);
PAINT MONO (-7725 3475);
DISPLAY INVISIBLE (-7725 3475);
FORCEPROP 1 LAST BODY_TYPE PLUMBING
J 2
(-7725 3525);
DISPLAY 0.872340 (-7725 3525);
PAINT GREEN (-7725 3525);
DISPLAY INVISIBLE (-7725 3525);
FORCEPROP 1 LAST HDL_TAP TRUE
J 2
(-8050 3350);
DISPLAY 0.872340 (-8050 3350);
DISPLAY INVISIBLE (-8050 3350);
FORCEPROP 1 LAST PATH I29
J 2
(-7723 3475);
DISPLAY 0.872340 (-7723 3475);
PAINT GREEN (-7723 3475);
DISPLAY INVISIBLE (-7723 3475);
FORCEADD TAP..1
R 2
(-7725 3525);
FORCEPROP 3 LASTPIN (-7675 3525) SIG_NAME M_K_CPU0_SB_CB<7>
J 0
(-7665 3535);
DISPLAY 0.659574 (-7665 3535);
PAINT MONO (-7665 3535);
DISPLAY INVISIBLE (-7665 3535);
FORCEPROP 1 LASTPIN (-7675 3525) BN 7
J 2
(-7663 3533);
DISPLAY 0.489362 (-7663 3533);
PAINT GREEN (-7663 3533);
FORCEPROP 2 LAST CDS_LIB mstr_standard
J 0
(-7725 3525);
DISPLAY 0.723404 (-7725 3525);
PAINT MONO (-7725 3525);
DISPLAY INVISIBLE (-7725 3525);
FORCEPROP 1 LAST BODY_TYPE PLUMBING
J 2
(-7725 3575);
DISPLAY 0.872340 (-7725 3575);
PAINT GREEN (-7725 3575);
DISPLAY INVISIBLE (-7725 3575);
FORCEPROP 1 LAST HDL_TAP TRUE
J 2
(-8050 3400);
DISPLAY 0.872340 (-8050 3400);
DISPLAY INVISIBLE (-8050 3400);
FORCEPROP 1 LAST PATH I30
J 2
(-7723 3525);
DISPLAY 0.872340 (-7723 3525);
PAINT GREEN (-7723 3525);
DISPLAY INVISIBLE (-7723 3525);
FORCEADD TAP..1
R 2
(-7725 3625);
FORCEPROP 3 LASTPIN (-7675 3625) SIG_NAME M_K_CPU0_SA_CB<0>
J 0
(-7665 3635);
DISPLAY 0.659574 (-7665 3635);
PAINT MONO (-7665 3635);
DISPLAY INVISIBLE (-7665 3635);
FORCEPROP 1 LASTPIN (-7675 3625) BN 0
J 2
(-7663 3633);
DISPLAY 0.489362 (-7663 3633);
PAINT GREEN (-7663 3633);
FORCEPROP 2 LAST CDS_LIB mstr_standard
J 0
(-7725 3625);
DISPLAY 0.723404 (-7725 3625);
PAINT MONO (-7725 3625);
DISPLAY INVISIBLE (-7725 3625);
FORCEPROP 1 LAST BODY_TYPE PLUMBING
J 2
(-7725 3675);
DISPLAY 0.872340 (-7725 3675);
PAINT GREEN (-7725 3675);
DISPLAY INVISIBLE (-7725 3675);
FORCEPROP 1 LAST HDL_TAP TRUE
J 2
(-8050 3500);
DISPLAY 0.872340 (-8050 3500);
DISPLAY INVISIBLE (-8050 3500);
FORCEPROP 1 LAST PATH I31
J 2
(-7723 3625);
DISPLAY 0.872340 (-7723 3625);
PAINT GREEN (-7723 3625);
DISPLAY INVISIBLE (-7723 3625);
FORCEADD TAP..1
R 2
(-7725 3675);
FORCEPROP 3 LASTPIN (-7675 3675) SIG_NAME M_K_CPU0_SA_CB<1>
J 0
(-7665 3685);
DISPLAY 0.659574 (-7665 3685);
PAINT MONO (-7665 3685);
DISPLAY INVISIBLE (-7665 3685);
FORCEPROP 1 LASTPIN (-7675 3675) BN 1
J 2
(-7663 3683);
DISPLAY 0.489362 (-7663 3683);
PAINT GREEN (-7663 3683);
FORCEPROP 2 LAST CDS_LIB mstr_standard
J 0
(-7725 3675);
DISPLAY 0.723404 (-7725 3675);
PAINT MONO (-7725 3675);
DISPLAY INVISIBLE (-7725 3675);
FORCEPROP 1 LAST BODY_TYPE PLUMBING
J 2
(-7725 3725);
DISPLAY 0.872340 (-7725 3725);
PAINT GREEN (-7725 3725);
DISPLAY INVISIBLE (-7725 3725);
FORCEPROP 1 LAST HDL_TAP TRUE
J 2
(-8050 3550);
DISPLAY 0.872340 (-8050 3550);
DISPLAY INVISIBLE (-8050 3550);
FORCEPROP 1 LAST PATH I32
J 2
(-7723 3675);
DISPLAY 0.872340 (-7723 3675);
PAINT GREEN (-7723 3675);
DISPLAY INVISIBLE (-7723 3675);
FORCEADD TAP..1
R 2
(-7725 3725);
FORCEPROP 3 LASTPIN (-7675 3725) SIG_NAME M_K_CPU0_SA_CB<2>
J 0
(-7665 3735);
DISPLAY 0.659574 (-7665 3735);
PAINT MONO (-7665 3735);
DISPLAY INVISIBLE (-7665 3735);
FORCEPROP 1 LASTPIN (-7675 3725) BN 2
J 2
(-7663 3733);
DISPLAY 0.489362 (-7663 3733);
PAINT GREEN (-7663 3733);
FORCEPROP 2 LAST CDS_LIB mstr_standard
J 0
(-7725 3725);
DISPLAY 0.723404 (-7725 3725);
PAINT MONO (-7725 3725);
DISPLAY INVISIBLE (-7725 3725);
FORCEPROP 1 LAST BODY_TYPE PLUMBING
J 2
(-7725 3775);
DISPLAY 0.872340 (-7725 3775);
PAINT GREEN (-7725 3775);
DISPLAY INVISIBLE (-7725 3775);
FORCEPROP 1 LAST HDL_TAP TRUE
J 2
(-8050 3600);
DISPLAY 0.872340 (-8050 3600);
DISPLAY INVISIBLE (-8050 3600);
FORCEPROP 1 LAST PATH I33
J 2
(-7723 3725);
DISPLAY 0.872340 (-7723 3725);
PAINT GREEN (-7723 3725);
DISPLAY INVISIBLE (-7723 3725);
FORCEADD TAP..1
R 2
(-7725 3775);
FORCEPROP 3 LASTPIN (-7675 3775) SIG_NAME M_K_CPU0_SA_CB<3>
J 0
(-7665 3785);
DISPLAY 0.659574 (-7665 3785);
PAINT MONO (-7665 3785);
DISPLAY INVISIBLE (-7665 3785);
FORCEPROP 1 LASTPIN (-7675 3775) BN 3
J 2
(-7663 3783);
DISPLAY 0.489362 (-7663 3783);
PAINT GREEN (-7663 3783);
FORCEPROP 2 LAST CDS_LIB mstr_standard
J 0
(-7725 3775);
DISPLAY 0.723404 (-7725 3775);
PAINT MONO (-7725 3775);
DISPLAY INVISIBLE (-7725 3775);
FORCEPROP 1 LAST BODY_TYPE PLUMBING
J 2
(-7725 3825);
DISPLAY 0.872340 (-7725 3825);
PAINT GREEN (-7725 3825);
DISPLAY INVISIBLE (-7725 3825);
FORCEPROP 1 LAST HDL_TAP TRUE
J 2
(-8050 3650);
DISPLAY 0.872340 (-8050 3650);
DISPLAY INVISIBLE (-8050 3650);
FORCEPROP 1 LAST PATH I34
J 2
(-7723 3775);
DISPLAY 0.872340 (-7723 3775);
PAINT GREEN (-7723 3775);
DISPLAY INVISIBLE (-7723 3775);
FORCEADD TAP..1
R 2
(-7725 3875);
FORCEPROP 3 LASTPIN (-7675 3875) SIG_NAME M_K_CPU0_SA_CB<5>
J 0
(-7665 3885);
DISPLAY 0.659574 (-7665 3885);
PAINT MONO (-7665 3885);
DISPLAY INVISIBLE (-7665 3885);
FORCEPROP 1 LASTPIN (-7675 3875) BN 5
J 2
(-7663 3883);
DISPLAY 0.489362 (-7663 3883);
PAINT GREEN (-7663 3883);
FORCEPROP 2 LAST CDS_LIB mstr_standard
J 0
(-7725 3875);
DISPLAY 0.723404 (-7725 3875);
PAINT MONO (-7725 3875);
DISPLAY INVISIBLE (-7725 3875);
FORCEPROP 1 LAST BODY_TYPE PLUMBING
J 2
(-7725 3925);
DISPLAY 0.872340 (-7725 3925);
PAINT GREEN (-7725 3925);
DISPLAY INVISIBLE (-7725 3925);
FORCEPROP 1 LAST HDL_TAP TRUE
J 2
(-8050 3750);
DISPLAY 0.872340 (-8050 3750);
DISPLAY INVISIBLE (-8050 3750);
FORCEPROP 1 LAST PATH I35
J 2
(-7723 3875);
DISPLAY 0.872340 (-7723 3875);
PAINT GREEN (-7723 3875);
DISPLAY INVISIBLE (-7723 3875);
FORCEADD TAP..1
R 2
(-7725 3825);
FORCEPROP 3 LASTPIN (-7675 3825) SIG_NAME M_K_CPU0_SA_CB<4>
J 0
(-7665 3835);
DISPLAY 0.659574 (-7665 3835);
PAINT MONO (-7665 3835);
DISPLAY INVISIBLE (-7665 3835);
FORCEPROP 1 LASTPIN (-7675 3825) BN 4
J 2
(-7663 3833);
DISPLAY 0.489362 (-7663 3833);
PAINT GREEN (-7663 3833);
FORCEPROP 2 LAST CDS_LIB mstr_standard
J 0
(-7725 3825);
DISPLAY 0.723404 (-7725 3825);
PAINT MONO (-7725 3825);
DISPLAY INVISIBLE (-7725 3825);
FORCEPROP 1 LAST BODY_TYPE PLUMBING
J 2
(-7725 3875);
DISPLAY 0.872340 (-7725 3875);
PAINT GREEN (-7725 3875);
DISPLAY INVISIBLE (-7725 3875);
FORCEPROP 1 LAST HDL_TAP TRUE
J 2
(-8050 3700);
DISPLAY 0.872340 (-8050 3700);
DISPLAY INVISIBLE (-8050 3700);
FORCEPROP 1 LAST PATH I36
J 2
(-7723 3825);
DISPLAY 0.872340 (-7723 3825);
PAINT GREEN (-7723 3825);
DISPLAY INVISIBLE (-7723 3825);
FORCEADD TAP..1
(-6025 2175);
FORCEPROP 3 LASTPIN (-6075 2175) SIG_NAME M_K_CPU0_SB_DQ<0>
J 0
(-6065 2185);
DISPLAY 0.659574 (-6065 2185);
PAINT MONO (-6065 2185);
DISPLAY INVISIBLE (-6065 2185);
FORCEPROP 1 LASTPIN (-6075 2175) BN 0
J 0
(-6087 2183);
DISPLAY 0.489362 (-6087 2183);
PAINT GREEN (-6087 2183);
FORCEPROP 2 LAST CDS_LIB mstr_standard
J 0
(-6025 2175);
DISPLAY 0.723404 (-6025 2175);
PAINT MONO (-6025 2175);
DISPLAY INVISIBLE (-6025 2175);
FORCEPROP 1 LAST BODY_TYPE PLUMBING
J 0
(-6025 2225);
DISPLAY 0.872340 (-6025 2225);
PAINT GREEN (-6025 2225);
DISPLAY INVISIBLE (-6025 2225);
FORCEPROP 1 LAST HDL_TAP TRUE
J 0
(-5700 2050);
DISPLAY 0.872340 (-5700 2050);
DISPLAY INVISIBLE (-5700 2050);
FORCEPROP 1 LAST PATH I37
J 0
(-6027 2175);
DISPLAY 0.872340 (-6027 2175);
PAINT GREEN (-6027 2175);
DISPLAY INVISIBLE (-6027 2175);
FORCEADD TAP..1
(-6025 2225);
FORCEPROP 3 LASTPIN (-6075 2225) SIG_NAME M_K_CPU0_SB_DQ<1>
J 0
(-6065 2235);
DISPLAY 0.659574 (-6065 2235);
PAINT MONO (-6065 2235);
DISPLAY INVISIBLE (-6065 2235);
FORCEPROP 1 LASTPIN (-6075 2225) BN 1
J 0
(-6087 2233);
DISPLAY 0.489362 (-6087 2233);
PAINT GREEN (-6087 2233);
FORCEPROP 2 LAST CDS_LIB mstr_standard
J 0
(-6025 2225);
DISPLAY 0.723404 (-6025 2225);
PAINT MONO (-6025 2225);
DISPLAY INVISIBLE (-6025 2225);
FORCEPROP 1 LAST BODY_TYPE PLUMBING
J 0
(-6025 2275);
DISPLAY 0.872340 (-6025 2275);
PAINT GREEN (-6025 2275);
DISPLAY INVISIBLE (-6025 2275);
FORCEPROP 1 LAST HDL_TAP TRUE
J 0
(-5700 2100);
DISPLAY 0.872340 (-5700 2100);
DISPLAY INVISIBLE (-5700 2100);
FORCEPROP 1 LAST PATH I38
J 0
(-6027 2225);
DISPLAY 0.872340 (-6027 2225);
PAINT GREEN (-6027 2225);
DISPLAY INVISIBLE (-6027 2225);
FORCEADD TAP..1
(-6025 2275);
FORCEPROP 3 LASTPIN (-6075 2275) SIG_NAME M_K_CPU0_SB_DQ<2>
J 0
(-6065 2285);
DISPLAY 0.659574 (-6065 2285);
PAINT MONO (-6065 2285);
DISPLAY INVISIBLE (-6065 2285);
FORCEPROP 1 LASTPIN (-6075 2275) BN 2
J 0
(-6087 2283);
DISPLAY 0.489362 (-6087 2283);
PAINT GREEN (-6087 2283);
FORCEPROP 2 LAST CDS_LIB mstr_standard
J 0
(-6025 2275);
DISPLAY 0.723404 (-6025 2275);
PAINT MONO (-6025 2275);
DISPLAY INVISIBLE (-6025 2275);
FORCEPROP 1 LAST BODY_TYPE PLUMBING
J 0
(-6025 2325);
DISPLAY 0.872340 (-6025 2325);
PAINT GREEN (-6025 2325);
DISPLAY INVISIBLE (-6025 2325);
FORCEPROP 1 LAST HDL_TAP TRUE
J 0
(-5700 2150);
DISPLAY 0.872340 (-5700 2150);
DISPLAY INVISIBLE (-5700 2150);
FORCEPROP 1 LAST PATH I39
J 0
(-6027 2275);
DISPLAY 0.872340 (-6027 2275);
PAINT GREEN (-6027 2275);
DISPLAY INVISIBLE (-6027 2275);
FORCEADD OFFPAGE..1
(-8475 2875);
FORCEPROP 2 LAST $XR0 96 
J 0
(-8726 2875);
DISPLAY 0.638298 (-8726 2875);
PAINT MONO (-8726 2875);
FORCEPROP 2 LAST CDS_LIB mstr_standard
J 0
(-8475 2875);
DISPLAY 0.808511 (-8475 2875);
DISPLAY INVISIBLE (-8475 2875);
FORCEPROP 1 LAST OFFPAGE TRUE
J 0
(-8150 2750);
DISPLAY 0.872340 (-8150 2750);
PAINT GREEN (-8150 2750);
DISPLAY INVISIBLE (-8150 2750);
FORCEPROP 1 LAST COMMENT_BODY TRUE
J 0
(-8350 2775);
DISPLAY 0.872340 (-8350 2775);
PAINT GREEN (-8350 2775);
DISPLAY INVISIBLE (-8350 2775);
FORCEPROP 2 LAST PATH I4
J 0
(-8725 2925);
DISPLAY 1.021277 (-8725 2925);
DISPLAY INVISIBLE (-8725 2925);
FORCEADD TAP..1
(-6025 2325);
FORCEPROP 3 LASTPIN (-6075 2325) SIG_NAME M_K_CPU0_SB_DQ<3>
J 0
(-6065 2335);
DISPLAY 0.659574 (-6065 2335);
PAINT MONO (-6065 2335);
DISPLAY INVISIBLE (-6065 2335);
FORCEPROP 1 LASTPIN (-6075 2325) BN 3
J 0
(-6087 2333);
DISPLAY 0.489362 (-6087 2333);
PAINT GREEN (-6087 2333);
FORCEPROP 2 LAST CDS_LIB mstr_standard
J 0
(-6025 2325);
DISPLAY 0.723404 (-6025 2325);
PAINT MONO (-6025 2325);
DISPLAY INVISIBLE (-6025 2325);
FORCEPROP 1 LAST BODY_TYPE PLUMBING
J 0
(-6025 2375);
DISPLAY 0.872340 (-6025 2375);
PAINT GREEN (-6025 2375);
DISPLAY INVISIBLE (-6025 2375);
FORCEPROP 1 LAST HDL_TAP TRUE
J 0
(-5700 2200);
DISPLAY 0.872340 (-5700 2200);
DISPLAY INVISIBLE (-5700 2200);
FORCEPROP 1 LAST PATH I40
J 0
(-6027 2325);
DISPLAY 0.872340 (-6027 2325);
PAINT GREEN (-6027 2325);
DISPLAY INVISIBLE (-6027 2325);
FORCEADD TAP..1
(-6025 2375);
FORCEPROP 3 LASTPIN (-6075 2375) SIG_NAME M_K_CPU0_SB_DQ<4>
J 0
(-6065 2385);
DISPLAY 0.659574 (-6065 2385);
PAINT MONO (-6065 2385);
DISPLAY INVISIBLE (-6065 2385);
FORCEPROP 1 LASTPIN (-6075 2375) BN 4
J 0
(-6087 2383);
DISPLAY 0.489362 (-6087 2383);
PAINT GREEN (-6087 2383);
FORCEPROP 2 LAST CDS_LIB mstr_standard
J 0
(-6025 2375);
DISPLAY 0.723404 (-6025 2375);
PAINT MONO (-6025 2375);
DISPLAY INVISIBLE (-6025 2375);
FORCEPROP 1 LAST BODY_TYPE PLUMBING
J 0
(-6025 2425);
DISPLAY 0.872340 (-6025 2425);
PAINT GREEN (-6025 2425);
DISPLAY INVISIBLE (-6025 2425);
FORCEPROP 1 LAST HDL_TAP TRUE
J 0
(-5700 2250);
DISPLAY 0.872340 (-5700 2250);
DISPLAY INVISIBLE (-5700 2250);
FORCEPROP 1 LAST PATH I41
J 0
(-6027 2375);
DISPLAY 0.872340 (-6027 2375);
PAINT GREEN (-6027 2375);
DISPLAY INVISIBLE (-6027 2375);
FORCEADD TAP..1
(-6025 2475);
FORCEPROP 3 LASTPIN (-6075 2475) SIG_NAME M_K_CPU0_SB_DQ<6>
J 0
(-6065 2485);
DISPLAY 0.659574 (-6065 2485);
PAINT MONO (-6065 2485);
DISPLAY INVISIBLE (-6065 2485);
FORCEPROP 1 LASTPIN (-6075 2475) BN 6
J 0
(-6087 2483);
DISPLAY 0.489362 (-6087 2483);
PAINT GREEN (-6087 2483);
FORCEPROP 2 LAST CDS_LIB mstr_standard
J 0
(-6025 2475);
DISPLAY 0.723404 (-6025 2475);
PAINT MONO (-6025 2475);
DISPLAY INVISIBLE (-6025 2475);
FORCEPROP 1 LAST BODY_TYPE PLUMBING
J 0
(-6025 2525);
DISPLAY 0.872340 (-6025 2525);
PAINT GREEN (-6025 2525);
DISPLAY INVISIBLE (-6025 2525);
FORCEPROP 1 LAST HDL_TAP TRUE
J 0
(-5700 2350);
DISPLAY 0.872340 (-5700 2350);
DISPLAY INVISIBLE (-5700 2350);
FORCEPROP 1 LAST PATH I42
J 0
(-6027 2475);
DISPLAY 0.872340 (-6027 2475);
PAINT GREEN (-6027 2475);
DISPLAY INVISIBLE (-6027 2475);
FORCEADD TAP..1
(-6025 2425);
FORCEPROP 3 LASTPIN (-6075 2425) SIG_NAME M_K_CPU0_SB_DQ<5>
J 0
(-6065 2435);
DISPLAY 0.659574 (-6065 2435);
PAINT MONO (-6065 2435);
DISPLAY INVISIBLE (-6065 2435);
FORCEPROP 1 LASTPIN (-6075 2425) BN 5
J 0
(-6087 2433);
DISPLAY 0.489362 (-6087 2433);
PAINT GREEN (-6087 2433);
FORCEPROP 2 LAST CDS_LIB mstr_standard
J 0
(-6025 2425);
DISPLAY 0.723404 (-6025 2425);
PAINT MONO (-6025 2425);
DISPLAY INVISIBLE (-6025 2425);
FORCEPROP 1 LAST BODY_TYPE PLUMBING
J 0
(-6025 2475);
DISPLAY 0.872340 (-6025 2475);
PAINT GREEN (-6025 2475);
DISPLAY INVISIBLE (-6025 2475);
FORCEPROP 1 LAST HDL_TAP TRUE
J 0
(-5700 2300);
DISPLAY 0.872340 (-5700 2300);
DISPLAY INVISIBLE (-5700 2300);
FORCEPROP 1 LAST PATH I43
J 0
(-6027 2425);
DISPLAY 0.872340 (-6027 2425);
PAINT GREEN (-6027 2425);
DISPLAY INVISIBLE (-6027 2425);
FORCEADD TAP..1
(-6025 2575);
FORCEPROP 3 LASTPIN (-6075 2575) SIG_NAME M_K_CPU0_SB_DQ<8>
J 0
(-6065 2585);
DISPLAY 0.659574 (-6065 2585);
PAINT MONO (-6065 2585);
DISPLAY INVISIBLE (-6065 2585);
FORCEPROP 1 LASTPIN (-6075 2575) BN 8
J 0
(-6087 2583);
DISPLAY 0.489362 (-6087 2583);
PAINT GREEN (-6087 2583);
FORCEPROP 2 LAST CDS_LIB mstr_standard
J 0
(-6025 2575);
DISPLAY 0.723404 (-6025 2575);
PAINT MONO (-6025 2575);
DISPLAY INVISIBLE (-6025 2575);
FORCEPROP 1 LAST BODY_TYPE PLUMBING
J 0
(-6025 2625);
DISPLAY 0.872340 (-6025 2625);
PAINT GREEN (-6025 2625);
DISPLAY INVISIBLE (-6025 2625);
FORCEPROP 1 LAST HDL_TAP TRUE
J 0
(-5700 2450);
DISPLAY 0.872340 (-5700 2450);
DISPLAY INVISIBLE (-5700 2450);
FORCEPROP 1 LAST PATH I44
J 0
(-6027 2575);
DISPLAY 0.872340 (-6027 2575);
PAINT GREEN (-6027 2575);
DISPLAY INVISIBLE (-6027 2575);
FORCEADD TAP..1
(-6025 2525);
FORCEPROP 3 LASTPIN (-6075 2525) SIG_NAME M_K_CPU0_SB_DQ<7>
J 0
(-6065 2535);
DISPLAY 0.659574 (-6065 2535);
PAINT MONO (-6065 2535);
DISPLAY INVISIBLE (-6065 2535);
FORCEPROP 1 LASTPIN (-6075 2525) BN 7
J 0
(-6087 2533);
DISPLAY 0.489362 (-6087 2533);
PAINT GREEN (-6087 2533);
FORCEPROP 2 LAST CDS_LIB mstr_standard
J 0
(-6025 2525);
DISPLAY 0.723404 (-6025 2525);
PAINT MONO (-6025 2525);
DISPLAY INVISIBLE (-6025 2525);
FORCEPROP 1 LAST BODY_TYPE PLUMBING
J 0
(-6025 2575);
DISPLAY 0.872340 (-6025 2575);
PAINT GREEN (-6025 2575);
DISPLAY INVISIBLE (-6025 2575);
FORCEPROP 1 LAST HDL_TAP TRUE
J 0
(-5700 2400);
DISPLAY 0.872340 (-5700 2400);
DISPLAY INVISIBLE (-5700 2400);
FORCEPROP 1 LAST PATH I45
J 0
(-6027 2525);
DISPLAY 0.872340 (-6027 2525);
PAINT GREEN (-6027 2525);
DISPLAY INVISIBLE (-6027 2525);
FORCEADD TAP..1
(-6025 2625);
FORCEPROP 3 LASTPIN (-6075 2625) SIG_NAME M_K_CPU0_SB_DQ<9>
J 0
(-6065 2635);
DISPLAY 0.659574 (-6065 2635);
PAINT MONO (-6065 2635);
DISPLAY INVISIBLE (-6065 2635);
FORCEPROP 1 LASTPIN (-6075 2625) BN 9
J 0
(-6087 2633);
DISPLAY 0.489362 (-6087 2633);
PAINT GREEN (-6087 2633);
FORCEPROP 2 LAST CDS_LIB mstr_standard
J 0
(-6025 2625);
DISPLAY 0.723404 (-6025 2625);
PAINT MONO (-6025 2625);
DISPLAY INVISIBLE (-6025 2625);
FORCEPROP 1 LAST BODY_TYPE PLUMBING
J 0
(-6025 2675);
DISPLAY 0.872340 (-6025 2675);
PAINT GREEN (-6025 2675);
DISPLAY INVISIBLE (-6025 2675);
FORCEPROP 1 LAST HDL_TAP TRUE
J 0
(-5700 2500);
DISPLAY 0.872340 (-5700 2500);
DISPLAY INVISIBLE (-5700 2500);
FORCEPROP 1 LAST PATH I46
J 0
(-6027 2625);
DISPLAY 0.872340 (-6027 2625);
PAINT GREEN (-6027 2625);
DISPLAY INVISIBLE (-6027 2625);
FORCEADD TAP..1
(-6025 2725);
FORCEPROP 3 LASTPIN (-6075 2725) SIG_NAME M_K_CPU0_SB_DQ<11>
J 0
(-6065 2735);
DISPLAY 0.659574 (-6065 2735);
PAINT MONO (-6065 2735);
DISPLAY INVISIBLE (-6065 2735);
FORCEPROP 1 LASTPIN (-6075 2725) BN 11
J 0
(-6087 2733);
DISPLAY 0.489362 (-6087 2733);
PAINT GREEN (-6087 2733);
FORCEPROP 2 LAST CDS_LIB mstr_standard
J 0
(-6025 2725);
DISPLAY 0.723404 (-6025 2725);
PAINT MONO (-6025 2725);
DISPLAY INVISIBLE (-6025 2725);
FORCEPROP 1 LAST BODY_TYPE PLUMBING
J 0
(-6025 2775);
DISPLAY 0.872340 (-6025 2775);
PAINT GREEN (-6025 2775);
DISPLAY INVISIBLE (-6025 2775);
FORCEPROP 1 LAST HDL_TAP TRUE
J 0
(-5700 2600);
DISPLAY 0.872340 (-5700 2600);
DISPLAY INVISIBLE (-5700 2600);
FORCEPROP 1 LAST PATH I47
J 0
(-6027 2725);
DISPLAY 0.872340 (-6027 2725);
PAINT GREEN (-6027 2725);
DISPLAY INVISIBLE (-6027 2725);
FORCEADD TAP..1
(-6025 2675);
FORCEPROP 3 LASTPIN (-6075 2675) SIG_NAME M_K_CPU0_SB_DQ<10>
J 0
(-6065 2685);
DISPLAY 0.659574 (-6065 2685);
PAINT MONO (-6065 2685);
DISPLAY INVISIBLE (-6065 2685);
FORCEPROP 1 LASTPIN (-6075 2675) BN 10
J 0
(-6087 2683);
DISPLAY 0.489362 (-6087 2683);
PAINT GREEN (-6087 2683);
FORCEPROP 2 LAST CDS_LIB mstr_standard
J 0
(-6025 2675);
DISPLAY 0.723404 (-6025 2675);
PAINT MONO (-6025 2675);
DISPLAY INVISIBLE (-6025 2675);
FORCEPROP 1 LAST BODY_TYPE PLUMBING
J 0
(-6025 2725);
DISPLAY 0.872340 (-6025 2725);
PAINT GREEN (-6025 2725);
DISPLAY INVISIBLE (-6025 2725);
FORCEPROP 1 LAST HDL_TAP TRUE
J 0
(-5700 2550);
DISPLAY 0.872340 (-5700 2550);
DISPLAY INVISIBLE (-5700 2550);
FORCEPROP 1 LAST PATH I48
J 0
(-6027 2675);
DISPLAY 0.872340 (-6027 2675);
PAINT GREEN (-6027 2675);
DISPLAY INVISIBLE (-6027 2675);
FORCEADD TAP..1
(-6025 2775);
FORCEPROP 3 LASTPIN (-6075 2775) SIG_NAME M_K_CPU0_SB_DQ<12>
J 0
(-6065 2785);
DISPLAY 0.659574 (-6065 2785);
PAINT MONO (-6065 2785);
DISPLAY INVISIBLE (-6065 2785);
FORCEPROP 1 LASTPIN (-6075 2775) BN 12
J 0
(-6087 2783);
DISPLAY 0.489362 (-6087 2783);
PAINT GREEN (-6087 2783);
FORCEPROP 2 LAST CDS_LIB mstr_standard
J 0
(-6025 2775);
DISPLAY 0.723404 (-6025 2775);
PAINT MONO (-6025 2775);
DISPLAY INVISIBLE (-6025 2775);
FORCEPROP 1 LAST BODY_TYPE PLUMBING
J 0
(-6025 2825);
DISPLAY 0.872340 (-6025 2825);
PAINT GREEN (-6025 2825);
DISPLAY INVISIBLE (-6025 2825);
FORCEPROP 1 LAST HDL_TAP TRUE
J 0
(-5700 2650);
DISPLAY 0.872340 (-5700 2650);
DISPLAY INVISIBLE (-5700 2650);
FORCEPROP 1 LAST PATH I49
J 0
(-6027 2775);
DISPLAY 0.872340 (-6027 2775);
PAINT GREEN (-6027 2775);
DISPLAY INVISIBLE (-6027 2775);
FORCEADD OFFPAGE..5
(-8325 1975);
FORCEPROP 2 LAST $XR0 20 
J 0
(-8549 1975);
DISPLAY 0.638298 (-8549 1975);
PAINT MONO (-8549 1975);
FORCEPROP 2 LAST CDS_LIB mstr_standard
J 0
(-8325 1975);
DISPLAY 0.808511 (-8325 1975);
DISPLAY INVISIBLE (-8325 1975);
FORCEPROP 1 LAST OFFPAGE TRUE
J 0
(-8000 1850);
DISPLAY 0.872340 (-8000 1850);
PAINT GREEN (-8000 1850);
DISPLAY INVISIBLE (-8000 1850);
FORCEPROP 1 LAST COMMENT_BODY TRUE
J 0
(-8225 1900);
DISPLAY 0.872340 (-8225 1900);
PAINT GREEN (-8225 1900);
DISPLAY INVISIBLE (-8225 1900);
FORCEPROP 2 LAST PATH I5
J 0
(-8275 2050);
DISPLAY 1.021277 (-8275 2050);
DISPLAY INVISIBLE (-8275 2050);
FORCEADD TAP..1
(-6025 2825);
FORCEPROP 3 LASTPIN (-6075 2825) SIG_NAME M_K_CPU0_SB_DQ<13>
J 0
(-6065 2835);
DISPLAY 0.659574 (-6065 2835);
PAINT MONO (-6065 2835);
DISPLAY INVISIBLE (-6065 2835);
FORCEPROP 1 LASTPIN (-6075 2825) BN 13
J 0
(-6087 2833);
DISPLAY 0.489362 (-6087 2833);
PAINT GREEN (-6087 2833);
FORCEPROP 2 LAST CDS_LIB mstr_standard
J 0
(-6025 2825);
DISPLAY 0.723404 (-6025 2825);
PAINT MONO (-6025 2825);
DISPLAY INVISIBLE (-6025 2825);
FORCEPROP 1 LAST BODY_TYPE PLUMBING
J 0
(-6025 2875);
DISPLAY 0.872340 (-6025 2875);
PAINT GREEN (-6025 2875);
DISPLAY INVISIBLE (-6025 2875);
FORCEPROP 1 LAST HDL_TAP TRUE
J 0
(-5700 2700);
DISPLAY 0.872340 (-5700 2700);
DISPLAY INVISIBLE (-5700 2700);
FORCEPROP 1 LAST PATH I50
J 0
(-6027 2825);
DISPLAY 0.872340 (-6027 2825);
PAINT GREEN (-6027 2825);
DISPLAY INVISIBLE (-6027 2825);
FORCEADD TAP..1
(-6025 2875);
FORCEPROP 3 LASTPIN (-6075 2875) SIG_NAME M_K_CPU0_SB_DQ<14>
J 0
(-6065 2885);
DISPLAY 0.659574 (-6065 2885);
PAINT MONO (-6065 2885);
DISPLAY INVISIBLE (-6065 2885);
FORCEPROP 1 LASTPIN (-6075 2875) BN 14
J 0
(-6087 2883);
DISPLAY 0.489362 (-6087 2883);
PAINT GREEN (-6087 2883);
FORCEPROP 2 LAST CDS_LIB mstr_standard
J 0
(-6025 2875);
DISPLAY 0.723404 (-6025 2875);
PAINT MONO (-6025 2875);
DISPLAY INVISIBLE (-6025 2875);
FORCEPROP 1 LAST BODY_TYPE PLUMBING
J 0
(-6025 2925);
DISPLAY 0.872340 (-6025 2925);
PAINT GREEN (-6025 2925);
DISPLAY INVISIBLE (-6025 2925);
FORCEPROP 1 LAST HDL_TAP TRUE
J 0
(-5700 2750);
DISPLAY 0.872340 (-5700 2750);
DISPLAY INVISIBLE (-5700 2750);
FORCEPROP 1 LAST PATH I51
J 0
(-6027 2875);
DISPLAY 0.872340 (-6027 2875);
PAINT GREEN (-6027 2875);
DISPLAY INVISIBLE (-6027 2875);
FORCEADD TAP..1
(-6025 2975);
FORCEPROP 3 LASTPIN (-6075 2975) SIG_NAME M_K_CPU0_SB_DQ<16>
J 0
(-6065 2985);
DISPLAY 0.659574 (-6065 2985);
PAINT MONO (-6065 2985);
DISPLAY INVISIBLE (-6065 2985);
FORCEPROP 1 LASTPIN (-6075 2975) BN 16
J 0
(-6087 2983);
DISPLAY 0.489362 (-6087 2983);
PAINT GREEN (-6087 2983);
FORCEPROP 2 LAST CDS_LIB mstr_standard
J 0
(-6025 2975);
DISPLAY 0.723404 (-6025 2975);
PAINT MONO (-6025 2975);
DISPLAY INVISIBLE (-6025 2975);
FORCEPROP 1 LAST BODY_TYPE PLUMBING
J 0
(-6025 3025);
DISPLAY 0.872340 (-6025 3025);
PAINT GREEN (-6025 3025);
DISPLAY INVISIBLE (-6025 3025);
FORCEPROP 1 LAST HDL_TAP TRUE
J 0
(-5700 2850);
DISPLAY 0.872340 (-5700 2850);
DISPLAY INVISIBLE (-5700 2850);
FORCEPROP 1 LAST PATH I52
J 0
(-6027 2975);
DISPLAY 0.872340 (-6027 2975);
PAINT GREEN (-6027 2975);
DISPLAY INVISIBLE (-6027 2975);
FORCEADD TAP..1
(-6025 2925);
FORCEPROP 3 LASTPIN (-6075 2925) SIG_NAME M_K_CPU0_SB_DQ<15>
J 0
(-6065 2935);
DISPLAY 0.659574 (-6065 2935);
PAINT MONO (-6065 2935);
DISPLAY INVISIBLE (-6065 2935);
FORCEPROP 1 LASTPIN (-6075 2925) BN 15
J 0
(-6087 2933);
DISPLAY 0.489362 (-6087 2933);
PAINT GREEN (-6087 2933);
FORCEPROP 2 LAST CDS_LIB mstr_standard
J 0
(-6025 2925);
DISPLAY 0.723404 (-6025 2925);
PAINT MONO (-6025 2925);
DISPLAY INVISIBLE (-6025 2925);
FORCEPROP 1 LAST BODY_TYPE PLUMBING
J 0
(-6025 2975);
DISPLAY 0.872340 (-6025 2975);
PAINT GREEN (-6025 2975);
DISPLAY INVISIBLE (-6025 2975);
FORCEPROP 1 LAST HDL_TAP TRUE
J 0
(-5700 2800);
DISPLAY 0.872340 (-5700 2800);
DISPLAY INVISIBLE (-5700 2800);
FORCEPROP 1 LAST PATH I53
J 0
(-6027 2925);
DISPLAY 0.872340 (-6027 2925);
PAINT GREEN (-6027 2925);
DISPLAY INVISIBLE (-6027 2925);
FORCEADD TAP..1
(-6025 3025);
FORCEPROP 3 LASTPIN (-6075 3025) SIG_NAME M_K_CPU0_SB_DQ<17>
J 0
(-6065 3035);
DISPLAY 0.659574 (-6065 3035);
PAINT MONO (-6065 3035);
DISPLAY INVISIBLE (-6065 3035);
FORCEPROP 1 LASTPIN (-6075 3025) BN 17
J 0
(-6087 3033);
DISPLAY 0.489362 (-6087 3033);
PAINT GREEN (-6087 3033);
FORCEPROP 2 LAST CDS_LIB mstr_standard
J 0
(-6025 3025);
DISPLAY 0.723404 (-6025 3025);
PAINT MONO (-6025 3025);
DISPLAY INVISIBLE (-6025 3025);
FORCEPROP 1 LAST BODY_TYPE PLUMBING
J 0
(-6025 3075);
DISPLAY 0.872340 (-6025 3075);
PAINT GREEN (-6025 3075);
DISPLAY INVISIBLE (-6025 3075);
FORCEPROP 1 LAST HDL_TAP TRUE
J 0
(-5700 2900);
DISPLAY 0.872340 (-5700 2900);
DISPLAY INVISIBLE (-5700 2900);
FORCEPROP 1 LAST PATH I54
J 0
(-6027 3025);
DISPLAY 0.872340 (-6027 3025);
PAINT GREEN (-6027 3025);
DISPLAY INVISIBLE (-6027 3025);
FORCEADD TAP..1
(-6025 3075);
FORCEPROP 3 LASTPIN (-6075 3075) SIG_NAME M_K_CPU0_SB_DQ<18>
J 0
(-6065 3085);
DISPLAY 0.659574 (-6065 3085);
PAINT MONO (-6065 3085);
DISPLAY INVISIBLE (-6065 3085);
FORCEPROP 1 LASTPIN (-6075 3075) BN 18
J 0
(-6087 3083);
DISPLAY 0.489362 (-6087 3083);
PAINT GREEN (-6087 3083);
FORCEPROP 2 LAST CDS_LIB mstr_standard
J 0
(-6025 3075);
DISPLAY 0.723404 (-6025 3075);
PAINT MONO (-6025 3075);
DISPLAY INVISIBLE (-6025 3075);
FORCEPROP 1 LAST BODY_TYPE PLUMBING
J 0
(-6025 3125);
DISPLAY 0.872340 (-6025 3125);
PAINT GREEN (-6025 3125);
DISPLAY INVISIBLE (-6025 3125);
FORCEPROP 1 LAST HDL_TAP TRUE
J 0
(-5700 2950);
DISPLAY 0.872340 (-5700 2950);
DISPLAY INVISIBLE (-5700 2950);
FORCEPROP 1 LAST PATH I55
J 0
(-6027 3075);
DISPLAY 0.872340 (-6027 3075);
PAINT GREEN (-6027 3075);
DISPLAY INVISIBLE (-6027 3075);
FORCEADD TAP..1
(-6025 3125);
FORCEPROP 3 LASTPIN (-6075 3125) SIG_NAME M_K_CPU0_SB_DQ<19>
J 0
(-6065 3135);
DISPLAY 0.659574 (-6065 3135);
PAINT MONO (-6065 3135);
DISPLAY INVISIBLE (-6065 3135);
FORCEPROP 1 LASTPIN (-6075 3125) BN 19
J 0
(-6087 3133);
DISPLAY 0.489362 (-6087 3133);
PAINT GREEN (-6087 3133);
FORCEPROP 2 LAST CDS_LIB mstr_standard
J 0
(-6025 3125);
DISPLAY 0.723404 (-6025 3125);
PAINT MONO (-6025 3125);
DISPLAY INVISIBLE (-6025 3125);
FORCEPROP 1 LAST BODY_TYPE PLUMBING
J 0
(-6025 3175);
DISPLAY 0.872340 (-6025 3175);
PAINT GREEN (-6025 3175);
DISPLAY INVISIBLE (-6025 3175);
FORCEPROP 1 LAST HDL_TAP TRUE
J 0
(-5700 3000);
DISPLAY 0.872340 (-5700 3000);
DISPLAY INVISIBLE (-5700 3000);
FORCEPROP 1 LAST PATH I56
J 0
(-6027 3125);
DISPLAY 0.872340 (-6027 3125);
PAINT GREEN (-6027 3125);
DISPLAY INVISIBLE (-6027 3125);
FORCEADD TAP..1
(-6025 3175);
FORCEPROP 3 LASTPIN (-6075 3175) SIG_NAME M_K_CPU0_SB_DQ<20>
J 0
(-6065 3185);
DISPLAY 0.659574 (-6065 3185);
PAINT MONO (-6065 3185);
DISPLAY INVISIBLE (-6065 3185);
FORCEPROP 1 LASTPIN (-6075 3175) BN 20
J 0
(-6087 3183);
DISPLAY 0.489362 (-6087 3183);
PAINT GREEN (-6087 3183);
FORCEPROP 2 LAST CDS_LIB mstr_standard
J 0
(-6025 3175);
DISPLAY 0.723404 (-6025 3175);
PAINT MONO (-6025 3175);
DISPLAY INVISIBLE (-6025 3175);
FORCEPROP 1 LAST BODY_TYPE PLUMBING
J 0
(-6025 3225);
DISPLAY 0.872340 (-6025 3225);
PAINT GREEN (-6025 3225);
DISPLAY INVISIBLE (-6025 3225);
FORCEPROP 1 LAST HDL_TAP TRUE
J 0
(-5700 3050);
DISPLAY 0.872340 (-5700 3050);
DISPLAY INVISIBLE (-5700 3050);
FORCEPROP 1 LAST PATH I57
J 0
(-6027 3175);
DISPLAY 0.872340 (-6027 3175);
PAINT GREEN (-6027 3175);
DISPLAY INVISIBLE (-6027 3175);
FORCEADD TAP..1
(-6025 3225);
FORCEPROP 3 LASTPIN (-6075 3225) SIG_NAME M_K_CPU0_SB_DQ<21>
J 0
(-6065 3235);
DISPLAY 0.659574 (-6065 3235);
PAINT MONO (-6065 3235);
DISPLAY INVISIBLE (-6065 3235);
FORCEPROP 1 LASTPIN (-6075 3225) BN 21
J 0
(-6087 3233);
DISPLAY 0.489362 (-6087 3233);
PAINT GREEN (-6087 3233);
FORCEPROP 2 LAST CDS_LIB mstr_standard
J 0
(-6025 3225);
DISPLAY 0.723404 (-6025 3225);
PAINT MONO (-6025 3225);
DISPLAY INVISIBLE (-6025 3225);
FORCEPROP 1 LAST BODY_TYPE PLUMBING
J 0
(-6025 3275);
DISPLAY 0.872340 (-6025 3275);
PAINT GREEN (-6025 3275);
DISPLAY INVISIBLE (-6025 3275);
FORCEPROP 1 LAST HDL_TAP TRUE
J 0
(-5700 3100);
DISPLAY 0.872340 (-5700 3100);
DISPLAY INVISIBLE (-5700 3100);
FORCEPROP 1 LAST PATH I58
J 0
(-6027 3225);
DISPLAY 0.872340 (-6027 3225);
PAINT GREEN (-6027 3225);
DISPLAY INVISIBLE (-6027 3225);
FORCEADD TAP..1
(-6025 3275);
FORCEPROP 3 LASTPIN (-6075 3275) SIG_NAME M_K_CPU0_SB_DQ<22>
J 0
(-6065 3285);
DISPLAY 0.659574 (-6065 3285);
PAINT MONO (-6065 3285);
DISPLAY INVISIBLE (-6065 3285);
FORCEPROP 1 LASTPIN (-6075 3275) BN 22
J 0
(-6087 3283);
DISPLAY 0.489362 (-6087 3283);
PAINT GREEN (-6087 3283);
FORCEPROP 2 LAST CDS_LIB mstr_standard
J 0
(-6025 3275);
DISPLAY 0.723404 (-6025 3275);
PAINT MONO (-6025 3275);
DISPLAY INVISIBLE (-6025 3275);
FORCEPROP 1 LAST BODY_TYPE PLUMBING
J 0
(-6025 3325);
DISPLAY 0.872340 (-6025 3325);
PAINT GREEN (-6025 3325);
DISPLAY INVISIBLE (-6025 3325);
FORCEPROP 1 LAST HDL_TAP TRUE
J 0
(-5700 3150);
DISPLAY 0.872340 (-5700 3150);
DISPLAY INVISIBLE (-5700 3150);
FORCEPROP 1 LAST PATH I59
J 0
(-6027 3275);
DISPLAY 0.872340 (-6027 3275);
PAINT GREEN (-6027 3275);
DISPLAY INVISIBLE (-6027 3275);
FORCEADD OFFPAGE..5
(-8325 1925);
FORCEPROP 2 LAST $XR0 20 
J 0
(-8549 1925);
DISPLAY 0.638298 (-8549 1925);
PAINT MONO (-8549 1925);
FORCEPROP 2 LAST CDS_LIB mstr_standard
J 0
(-8325 1925);
DISPLAY 0.808511 (-8325 1925);
DISPLAY INVISIBLE (-8325 1925);
FORCEPROP 1 LAST OFFPAGE TRUE
J 0
(-8000 1800);
DISPLAY 0.872340 (-8000 1800);
PAINT GREEN (-8000 1800);
DISPLAY INVISIBLE (-8000 1800);
FORCEPROP 1 LAST COMMENT_BODY TRUE
J 0
(-8225 1850);
DISPLAY 0.872340 (-8225 1850);
PAINT GREEN (-8225 1850);
DISPLAY INVISIBLE (-8225 1850);
FORCEPROP 2 LAST PATH I6
J 0
(-8275 2000);
DISPLAY 1.021277 (-8275 2000);
DISPLAY INVISIBLE (-8275 2000);
FORCEADD TAP..1
(-6025 3375);
FORCEPROP 3 LASTPIN (-6075 3375) SIG_NAME M_K_CPU0_SB_DQ<24>
J 0
(-6065 3385);
DISPLAY 0.659574 (-6065 3385);
PAINT MONO (-6065 3385);
DISPLAY INVISIBLE (-6065 3385);
FORCEPROP 1 LASTPIN (-6075 3375) BN 24
J 0
(-6087 3383);
DISPLAY 0.489362 (-6087 3383);
PAINT GREEN (-6087 3383);
FORCEPROP 2 LAST CDS_LIB mstr_standard
J 0
(-6025 3375);
DISPLAY 0.723404 (-6025 3375);
PAINT MONO (-6025 3375);
DISPLAY INVISIBLE (-6025 3375);
FORCEPROP 1 LAST BODY_TYPE PLUMBING
J 0
(-6025 3425);
DISPLAY 0.872340 (-6025 3425);
PAINT GREEN (-6025 3425);
DISPLAY INVISIBLE (-6025 3425);
FORCEPROP 1 LAST HDL_TAP TRUE
J 0
(-5700 3250);
DISPLAY 0.872340 (-5700 3250);
DISPLAY INVISIBLE (-5700 3250);
FORCEPROP 1 LAST PATH I60
J 0
(-6027 3375);
DISPLAY 0.872340 (-6027 3375);
PAINT GREEN (-6027 3375);
DISPLAY INVISIBLE (-6027 3375);
FORCEADD TAP..1
(-6025 3325);
FORCEPROP 3 LASTPIN (-6075 3325) SIG_NAME M_K_CPU0_SB_DQ<23>
J 0
(-6065 3335);
DISPLAY 0.659574 (-6065 3335);
PAINT MONO (-6065 3335);
DISPLAY INVISIBLE (-6065 3335);
FORCEPROP 1 LASTPIN (-6075 3325) BN 23
J 0
(-6087 3333);
DISPLAY 0.489362 (-6087 3333);
PAINT GREEN (-6087 3333);
FORCEPROP 2 LAST CDS_LIB mstr_standard
J 0
(-6025 3325);
DISPLAY 0.723404 (-6025 3325);
PAINT MONO (-6025 3325);
DISPLAY INVISIBLE (-6025 3325);
FORCEPROP 1 LAST BODY_TYPE PLUMBING
J 0
(-6025 3375);
DISPLAY 0.872340 (-6025 3375);
PAINT GREEN (-6025 3375);
DISPLAY INVISIBLE (-6025 3375);
FORCEPROP 1 LAST HDL_TAP TRUE
J 0
(-5700 3200);
DISPLAY 0.872340 (-5700 3200);
DISPLAY INVISIBLE (-5700 3200);
FORCEPROP 1 LAST PATH I61
J 0
(-6027 3325);
DISPLAY 0.872340 (-6027 3325);
PAINT GREEN (-6027 3325);
DISPLAY INVISIBLE (-6027 3325);
FORCEADD TAP..1
(-6025 3425);
FORCEPROP 3 LASTPIN (-6075 3425) SIG_NAME M_K_CPU0_SB_DQ<25>
J 0
(-6065 3435);
DISPLAY 0.659574 (-6065 3435);
PAINT MONO (-6065 3435);
DISPLAY INVISIBLE (-6065 3435);
FORCEPROP 1 LASTPIN (-6075 3425) BN 25
J 0
(-6087 3433);
DISPLAY 0.489362 (-6087 3433);
PAINT GREEN (-6087 3433);
FORCEPROP 2 LAST CDS_LIB mstr_standard
J 0
(-6025 3425);
DISPLAY 0.723404 (-6025 3425);
PAINT MONO (-6025 3425);
DISPLAY INVISIBLE (-6025 3425);
FORCEPROP 1 LAST BODY_TYPE PLUMBING
J 0
(-6025 3475);
DISPLAY 0.872340 (-6025 3475);
PAINT GREEN (-6025 3475);
DISPLAY INVISIBLE (-6025 3475);
FORCEPROP 1 LAST HDL_TAP TRUE
J 0
(-5700 3300);
DISPLAY 0.872340 (-5700 3300);
DISPLAY INVISIBLE (-5700 3300);
FORCEPROP 1 LAST PATH I62
J 0
(-6027 3425);
DISPLAY 0.872340 (-6027 3425);
PAINT GREEN (-6027 3425);
DISPLAY INVISIBLE (-6027 3425);
FORCEADD TAP..1
(-6025 3475);
FORCEPROP 3 LASTPIN (-6075 3475) SIG_NAME M_K_CPU0_SB_DQ<26>
J 0
(-6065 3485);
DISPLAY 0.659574 (-6065 3485);
PAINT MONO (-6065 3485);
DISPLAY INVISIBLE (-6065 3485);
FORCEPROP 1 LASTPIN (-6075 3475) BN 26
J 0
(-6087 3483);
DISPLAY 0.489362 (-6087 3483);
PAINT GREEN (-6087 3483);
FORCEPROP 2 LAST CDS_LIB mstr_standard
J 0
(-6025 3475);
DISPLAY 0.723404 (-6025 3475);
PAINT MONO (-6025 3475);
DISPLAY INVISIBLE (-6025 3475);
FORCEPROP 1 LAST BODY_TYPE PLUMBING
J 0
(-6025 3525);
DISPLAY 0.872340 (-6025 3525);
PAINT GREEN (-6025 3525);
DISPLAY INVISIBLE (-6025 3525);
FORCEPROP 1 LAST HDL_TAP TRUE
J 0
(-5700 3350);
DISPLAY 0.872340 (-5700 3350);
DISPLAY INVISIBLE (-5700 3350);
FORCEPROP 1 LAST PATH I63
J 0
(-6027 3475);
DISPLAY 0.872340 (-6027 3475);
PAINT GREEN (-6027 3475);
DISPLAY INVISIBLE (-6027 3475);
FORCEADD TAP..1
(-6025 3525);
FORCEPROP 3 LASTPIN (-6075 3525) SIG_NAME M_K_CPU0_SB_DQ<27>
J 0
(-6065 3535);
DISPLAY 0.659574 (-6065 3535);
PAINT MONO (-6065 3535);
DISPLAY INVISIBLE (-6065 3535);
FORCEPROP 1 LASTPIN (-6075 3525) BN 27
J 0
(-6087 3533);
DISPLAY 0.489362 (-6087 3533);
PAINT GREEN (-6087 3533);
FORCEPROP 2 LAST CDS_LIB mstr_standard
J 0
(-6025 3525);
DISPLAY 0.723404 (-6025 3525);
PAINT MONO (-6025 3525);
DISPLAY INVISIBLE (-6025 3525);
FORCEPROP 1 LAST BODY_TYPE PLUMBING
J 0
(-6025 3575);
DISPLAY 0.872340 (-6025 3575);
PAINT GREEN (-6025 3575);
DISPLAY INVISIBLE (-6025 3575);
FORCEPROP 1 LAST HDL_TAP TRUE
J 0
(-5700 3400);
DISPLAY 0.872340 (-5700 3400);
DISPLAY INVISIBLE (-5700 3400);
FORCEPROP 1 LAST PATH I64
J 0
(-6027 3525);
DISPLAY 0.872340 (-6027 3525);
PAINT GREEN (-6027 3525);
DISPLAY INVISIBLE (-6027 3525);
FORCEADD TAP..1
(-6025 3625);
FORCEPROP 3 LASTPIN (-6075 3625) SIG_NAME M_K_CPU0_SB_DQ<29>
J 0
(-6065 3635);
DISPLAY 0.659574 (-6065 3635);
PAINT MONO (-6065 3635);
DISPLAY INVISIBLE (-6065 3635);
FORCEPROP 1 LASTPIN (-6075 3625) BN 29
J 0
(-6087 3633);
DISPLAY 0.489362 (-6087 3633);
PAINT GREEN (-6087 3633);
FORCEPROP 2 LAST CDS_LIB mstr_standard
J 0
(-6025 3625);
DISPLAY 0.723404 (-6025 3625);
PAINT MONO (-6025 3625);
DISPLAY INVISIBLE (-6025 3625);
FORCEPROP 1 LAST BODY_TYPE PLUMBING
J 0
(-6025 3675);
DISPLAY 0.872340 (-6025 3675);
PAINT GREEN (-6025 3675);
DISPLAY INVISIBLE (-6025 3675);
FORCEPROP 1 LAST HDL_TAP TRUE
J 0
(-5700 3500);
DISPLAY 0.872340 (-5700 3500);
DISPLAY INVISIBLE (-5700 3500);
FORCEPROP 1 LAST PATH I65
J 0
(-6027 3625);
DISPLAY 0.872340 (-6027 3625);
PAINT GREEN (-6027 3625);
DISPLAY INVISIBLE (-6027 3625);
FORCEADD TAP..1
(-6025 3575);
FORCEPROP 3 LASTPIN (-6075 3575) SIG_NAME M_K_CPU0_SB_DQ<28>
J 0
(-6065 3585);
DISPLAY 0.659574 (-6065 3585);
PAINT MONO (-6065 3585);
DISPLAY INVISIBLE (-6065 3585);
FORCEPROP 1 LASTPIN (-6075 3575) BN 28
J 0
(-6087 3583);
DISPLAY 0.489362 (-6087 3583);
PAINT GREEN (-6087 3583);
FORCEPROP 2 LAST CDS_LIB mstr_standard
J 0
(-6025 3575);
DISPLAY 0.723404 (-6025 3575);
PAINT MONO (-6025 3575);
DISPLAY INVISIBLE (-6025 3575);
FORCEPROP 1 LAST BODY_TYPE PLUMBING
J 0
(-6025 3625);
DISPLAY 0.872340 (-6025 3625);
PAINT GREEN (-6025 3625);
DISPLAY INVISIBLE (-6025 3625);
FORCEPROP 1 LAST HDL_TAP TRUE
J 0
(-5700 3450);
DISPLAY 0.872340 (-5700 3450);
DISPLAY INVISIBLE (-5700 3450);
FORCEPROP 1 LAST PATH I66
J 0
(-6027 3575);
DISPLAY 0.872340 (-6027 3575);
PAINT GREEN (-6027 3575);
DISPLAY INVISIBLE (-6027 3575);
FORCEADD TAP..1
(-6025 3725);
FORCEPROP 3 LASTPIN (-6075 3725) SIG_NAME M_K_CPU0_SB_DQ<31>
J 0
(-6065 3735);
DISPLAY 0.659574 (-6065 3735);
PAINT MONO (-6065 3735);
DISPLAY INVISIBLE (-6065 3735);
FORCEPROP 1 LASTPIN (-6075 3725) BN 31
J 0
(-6087 3733);
DISPLAY 0.489362 (-6087 3733);
PAINT GREEN (-6087 3733);
FORCEPROP 2 LAST CDS_LIB mstr_standard
J 0
(-6025 3725);
DISPLAY 0.723404 (-6025 3725);
PAINT MONO (-6025 3725);
DISPLAY INVISIBLE (-6025 3725);
FORCEPROP 1 LAST BODY_TYPE PLUMBING
J 0
(-6025 3775);
DISPLAY 0.872340 (-6025 3775);
PAINT GREEN (-6025 3775);
DISPLAY INVISIBLE (-6025 3775);
FORCEPROP 1 LAST HDL_TAP TRUE
J 0
(-5700 3600);
DISPLAY 0.872340 (-5700 3600);
DISPLAY INVISIBLE (-5700 3600);
FORCEPROP 1 LAST PATH I67
J 0
(-6027 3725);
DISPLAY 0.872340 (-6027 3725);
PAINT GREEN (-6027 3725);
DISPLAY INVISIBLE (-6027 3725);
FORCEADD TAP..1
(-6025 3675);
FORCEPROP 3 LASTPIN (-6075 3675) SIG_NAME M_K_CPU0_SB_DQ<30>
J 0
(-6065 3685);
DISPLAY 0.659574 (-6065 3685);
PAINT MONO (-6065 3685);
DISPLAY INVISIBLE (-6065 3685);
FORCEPROP 1 LASTPIN (-6075 3675) BN 30
J 0
(-6087 3683);
DISPLAY 0.489362 (-6087 3683);
PAINT GREEN (-6087 3683);
FORCEPROP 2 LAST CDS_LIB mstr_standard
J 0
(-6025 3675);
DISPLAY 0.723404 (-6025 3675);
PAINT MONO (-6025 3675);
DISPLAY INVISIBLE (-6025 3675);
FORCEPROP 1 LAST BODY_TYPE PLUMBING
J 0
(-6025 3725);
DISPLAY 0.872340 (-6025 3725);
PAINT GREEN (-6025 3725);
DISPLAY INVISIBLE (-6025 3725);
FORCEPROP 1 LAST HDL_TAP TRUE
J 0
(-5700 3550);
DISPLAY 0.872340 (-5700 3550);
DISPLAY INVISIBLE (-5700 3550);
FORCEPROP 1 LAST PATH I68
J 0
(-6027 3675);
DISPLAY 0.872340 (-6027 3675);
PAINT GREEN (-6027 3675);
DISPLAY INVISIBLE (-6027 3675);
FORCEADD TAP..1
(-6025 3825);
FORCEPROP 3 LASTPIN (-6075 3825) SIG_NAME M_K_CPU0_SA_DQ<0>
J 0
(-6065 3835);
DISPLAY 0.659574 (-6065 3835);
PAINT MONO (-6065 3835);
DISPLAY INVISIBLE (-6065 3835);
FORCEPROP 1 LASTPIN (-6075 3825) BN 0
J 0
(-6087 3833);
DISPLAY 0.489362 (-6087 3833);
PAINT GREEN (-6087 3833);
FORCEPROP 2 LAST CDS_LIB mstr_standard
J 0
(-6025 3825);
DISPLAY 0.723404 (-6025 3825);
PAINT MONO (-6025 3825);
DISPLAY INVISIBLE (-6025 3825);
FORCEPROP 1 LAST BODY_TYPE PLUMBING
J 0
(-6025 3875);
DISPLAY 0.872340 (-6025 3875);
PAINT GREEN (-6025 3875);
DISPLAY INVISIBLE (-6025 3875);
FORCEPROP 1 LAST HDL_TAP TRUE
J 0
(-5700 3700);
DISPLAY 0.872340 (-5700 3700);
DISPLAY INVISIBLE (-5700 3700);
FORCEPROP 1 LAST PATH I69
J 0
(-6027 3825);
DISPLAY 0.872340 (-6027 3825);
PAINT GREEN (-6027 3825);
DISPLAY INVISIBLE (-6027 3825);
FORCEADD OFFPAGE..5
(-8150 3025);
FORCEPROP 2 LAST $XR0 20 
J 0
(-8374 3025);
DISPLAY 0.638298 (-8374 3025);
PAINT MONO (-8374 3025);
FORCEPROP 2 LAST CDS_LIB mstr_standard
J 0
(-8150 3025);
DISPLAY INVISIBLE (-8150 3025);
FORCEPROP 1 LAST OFFPAGE TRUE
J 0
(-7825 2900);
DISPLAY 0.872340 (-7825 2900);
PAINT GREEN (-7825 2900);
DISPLAY INVISIBLE (-7825 2900);
FORCEPROP 1 LAST COMMENT_BODY TRUE
J 0
(-8050 2950);
DISPLAY 0.872340 (-8050 2950);
PAINT GREEN (-8050 2950);
DISPLAY INVISIBLE (-8050 2950);
FORCEPROP 2 LAST PATH I7
J 0
(-8100 3100);
DISPLAY 1.021277 (-8100 3100);
DISPLAY INVISIBLE (-8100 3100);
FORCEADD TAP..1
(-6025 3875);
FORCEPROP 3 LASTPIN (-6075 3875) SIG_NAME M_K_CPU0_SA_DQ<1>
J 0
(-6065 3885);
DISPLAY 0.659574 (-6065 3885);
PAINT MONO (-6065 3885);
DISPLAY INVISIBLE (-6065 3885);
FORCEPROP 1 LASTPIN (-6075 3875) BN 1
J 0
(-6087 3883);
DISPLAY 0.489362 (-6087 3883);
PAINT GREEN (-6087 3883);
FORCEPROP 2 LAST CDS_LIB mstr_standard
J 0
(-6025 3875);
DISPLAY 0.723404 (-6025 3875);
PAINT MONO (-6025 3875);
DISPLAY INVISIBLE (-6025 3875);
FORCEPROP 1 LAST BODY_TYPE PLUMBING
J 0
(-6025 3925);
DISPLAY 0.872340 (-6025 3925);
PAINT GREEN (-6025 3925);
DISPLAY INVISIBLE (-6025 3925);
FORCEPROP 1 LAST HDL_TAP TRUE
J 0
(-5700 3750);
DISPLAY 0.872340 (-5700 3750);
DISPLAY INVISIBLE (-5700 3750);
FORCEPROP 1 LAST PATH I70
J 0
(-6027 3875);
DISPLAY 0.872340 (-6027 3875);
PAINT GREEN (-6027 3875);
DISPLAY INVISIBLE (-6027 3875);
FORCEADD OFFPAGE..3
(-5350 3775);
FORCEPROP 2 LAST $XR0 20 
J 0
(-5136 3775);
DISPLAY 0.638298 (-5136 3775);
PAINT MONO (-5136 3775);
FORCEPROP 2 LAST CDS_LIB mstr_standard
J 0
(-5350 3775);
DISPLAY 0.723404 (-5350 3775);
PAINT MONO (-5350 3775);
DISPLAY INVISIBLE (-5350 3775);
FORCEPROP 1 LAST OFFPAGE TRUE
J 0
(-5025 3650);
DISPLAY 0.872340 (-5025 3650);
PAINT GREEN (-5025 3650);
DISPLAY INVISIBLE (-5025 3650);
FORCEPROP 1 LAST COMMENT_BODY TRUE
J 0
(-5400 3675);
DISPLAY 0.872340 (-5400 3675);
PAINT GREEN (-5400 3675);
DISPLAY INVISIBLE (-5400 3675);
FORCEPROP 2 LAST PATH I78
J 0
(-5150 3850);
DISPLAY 1.021277 (-5150 3850);
DISPLAY INVISIBLE (-5150 3850);
FORCEADD OFFPAGE..1
(-8150 3075);
FORCEPROP 2 LAST $XR0 20 
J 0
(-8401 3075);
DISPLAY 0.638298 (-8401 3075);
PAINT MONO (-8401 3075);
FORCEPROP 2 LAST CDS_LIB mstr_standard
J 0
(-8150 3075);
DISPLAY 0.808511 (-8150 3075);
DISPLAY INVISIBLE (-8150 3075);
FORCEPROP 1 LAST OFFPAGE TRUE
J 0
(-7825 2950);
DISPLAY 0.872340 (-7825 2950);
PAINT GREEN (-7825 2950);
DISPLAY INVISIBLE (-7825 2950);
FORCEPROP 1 LAST COMMENT_BODY TRUE
J 0
(-8025 2975);
DISPLAY 0.872340 (-8025 2975);
PAINT GREEN (-8025 2975);
DISPLAY INVISIBLE (-8025 2975);
FORCEPROP 2 LAST PATH I8
J 0
(-8575 3125);
DISPLAY 1.021277 (-8575 3125);
DISPLAY INVISIBLE (-8575 3125);
FORCEADD TAP..1
R 2
(-7725 3925);
FORCEPROP 3 LASTPIN (-7675 3925) SIG_NAME M_K_CPU0_SA_CB<6>
J 0
(-7665 3935);
DISPLAY 0.659574 (-7665 3935);
PAINT MONO (-7665 3935);
DISPLAY INVISIBLE (-7665 3935);
FORCEPROP 1 LASTPIN (-7675 3925) BN 6
J 2
(-7663 3933);
DISPLAY 0.489362 (-7663 3933);
PAINT GREEN (-7663 3933);
FORCEPROP 2 LAST CDS_LIB mstr_standard
J 0
(-7725 3925);
DISPLAY 0.723404 (-7725 3925);
PAINT MONO (-7725 3925);
DISPLAY INVISIBLE (-7725 3925);
FORCEPROP 1 LAST BODY_TYPE PLUMBING
J 2
(-7725 3975);
DISPLAY 0.872340 (-7725 3975);
PAINT GREEN (-7725 3975);
DISPLAY INVISIBLE (-7725 3975);
FORCEPROP 1 LAST HDL_TAP TRUE
J 2
(-8050 3800);
DISPLAY 0.872340 (-8050 3800);
DISPLAY INVISIBLE (-8050 3800);
FORCEPROP 1 LAST PATH I80
J 2
(-7723 3925);
DISPLAY 0.872340 (-7723 3925);
PAINT GREEN (-7723 3925);
DISPLAY INVISIBLE (-7723 3925);
FORCEADD TAP..1
R 2
(-7725 3975);
FORCEPROP 3 LASTPIN (-7675 3975) SIG_NAME M_K_CPU0_SA_CB<7>
J 0
(-7665 3985);
DISPLAY 0.659574 (-7665 3985);
PAINT MONO (-7665 3985);
DISPLAY INVISIBLE (-7665 3985);
FORCEPROP 1 LASTPIN (-7675 3975) BN 7
J 2
(-7663 3983);
DISPLAY 0.489362 (-7663 3983);
PAINT GREEN (-7663 3983);
FORCEPROP 2 LAST CDS_LIB mstr_standard
J 0
(-7725 3975);
DISPLAY 0.723404 (-7725 3975);
PAINT MONO (-7725 3975);
DISPLAY INVISIBLE (-7725 3975);
FORCEPROP 1 LAST BODY_TYPE PLUMBING
J 2
(-7725 4025);
DISPLAY 0.872340 (-7725 4025);
PAINT GREEN (-7725 4025);
DISPLAY INVISIBLE (-7725 4025);
FORCEPROP 1 LAST HDL_TAP TRUE
J 2
(-8050 3850);
DISPLAY 0.872340 (-8050 3850);
DISPLAY INVISIBLE (-8050 3850);
FORCEPROP 1 LAST PATH I81
J 2
(-7723 3975);
DISPLAY 0.872340 (-7723 3975);
PAINT GREEN (-7723 3975);
DISPLAY INVISIBLE (-7723 3975);
FORCEADD TAP..1
R 2
(-7725 4675);
FORCEPROP 3 LASTPIN (-7675 4675) SIG_NAME M_K_CPU0_SB_CA<0>
J 0
(-7665 4685);
DISPLAY 0.659574 (-7665 4685);
PAINT MONO (-7665 4685);
DISPLAY INVISIBLE (-7665 4685);
FORCEPROP 1 LASTPIN (-7675 4675) BN 0
J 2
(-7663 4683);
DISPLAY 0.489362 (-7663 4683);
PAINT GREEN (-7663 4683);
FORCEPROP 2 LAST CDS_LIB mstr_standard
J 0
(-7725 4675);
DISPLAY 0.723404 (-7725 4675);
PAINT MONO (-7725 4675);
DISPLAY INVISIBLE (-7725 4675);
FORCEPROP 1 LAST BODY_TYPE PLUMBING
J 2
(-7725 4725);
DISPLAY 0.872340 (-7725 4725);
PAINT GREEN (-7725 4725);
DISPLAY INVISIBLE (-7725 4725);
FORCEPROP 1 LAST HDL_TAP TRUE
J 2
(-8050 4550);
DISPLAY 0.872340 (-8050 4550);
DISPLAY INVISIBLE (-8050 4550);
FORCEPROP 1 LAST PATH I82
J 2
(-7723 4675);
DISPLAY 0.872340 (-7723 4675);
PAINT GREEN (-7723 4675);
DISPLAY INVISIBLE (-7723 4675);
FORCEADD TAP..1
R 2
(-7725 4775);
FORCEPROP 3 LASTPIN (-7675 4775) SIG_NAME M_K_CPU0_SB_CA<2>
J 0
(-7665 4785);
DISPLAY 0.659574 (-7665 4785);
PAINT MONO (-7665 4785);
DISPLAY INVISIBLE (-7665 4785);
FORCEPROP 1 LASTPIN (-7675 4775) BN 2
J 2
(-7663 4783);
DISPLAY 0.489362 (-7663 4783);
PAINT GREEN (-7663 4783);
FORCEPROP 2 LAST CDS_LIB mstr_standard
J 0
(-7725 4775);
DISPLAY 0.723404 (-7725 4775);
PAINT MONO (-7725 4775);
DISPLAY INVISIBLE (-7725 4775);
FORCEPROP 1 LAST BODY_TYPE PLUMBING
J 2
(-7725 4825);
DISPLAY 0.872340 (-7725 4825);
PAINT GREEN (-7725 4825);
DISPLAY INVISIBLE (-7725 4825);
FORCEPROP 1 LAST HDL_TAP TRUE
J 2
(-8050 4650);
DISPLAY 0.872340 (-8050 4650);
DISPLAY INVISIBLE (-8050 4650);
FORCEPROP 1 LAST PATH I83
J 2
(-7723 4775);
DISPLAY 0.872340 (-7723 4775);
PAINT GREEN (-7723 4775);
DISPLAY INVISIBLE (-7723 4775);
FORCEADD TAP..1
R 2
(-7725 4725);
FORCEPROP 3 LASTPIN (-7675 4725) SIG_NAME M_K_CPU0_SB_CA<1>
J 0
(-7665 4735);
DISPLAY 0.659574 (-7665 4735);
PAINT MONO (-7665 4735);
DISPLAY INVISIBLE (-7665 4735);
FORCEPROP 1 LASTPIN (-7675 4725) BN 1
J 2
(-7663 4733);
DISPLAY 0.489362 (-7663 4733);
PAINT GREEN (-7663 4733);
FORCEPROP 2 LAST CDS_LIB mstr_standard
J 0
(-7725 4725);
DISPLAY 0.723404 (-7725 4725);
PAINT MONO (-7725 4725);
DISPLAY INVISIBLE (-7725 4725);
FORCEPROP 1 LAST BODY_TYPE PLUMBING
J 2
(-7725 4775);
DISPLAY 0.872340 (-7725 4775);
PAINT GREEN (-7725 4775);
DISPLAY INVISIBLE (-7725 4775);
FORCEPROP 1 LAST HDL_TAP TRUE
J 2
(-8050 4600);
DISPLAY 0.872340 (-8050 4600);
DISPLAY INVISIBLE (-8050 4600);
FORCEPROP 1 LAST PATH I84
J 2
(-7723 4725);
DISPLAY 0.872340 (-7723 4725);
PAINT GREEN (-7723 4725);
DISPLAY INVISIBLE (-7723 4725);
FORCEADD TAP..1
R 2
(-7725 4875);
FORCEPROP 3 LASTPIN (-7675 4875) SIG_NAME M_K_CPU0_SB_CA<4>
J 0
(-7665 4885);
DISPLAY 0.659574 (-7665 4885);
PAINT MONO (-7665 4885);
DISPLAY INVISIBLE (-7665 4885);
FORCEPROP 1 LASTPIN (-7675 4875) BN 4
J 2
(-7663 4883);
DISPLAY 0.489362 (-7663 4883);
PAINT GREEN (-7663 4883);
FORCEPROP 2 LAST CDS_LIB mstr_standard
J 0
(-7725 4875);
DISPLAY 0.723404 (-7725 4875);
PAINT MONO (-7725 4875);
DISPLAY INVISIBLE (-7725 4875);
FORCEPROP 1 LAST BODY_TYPE PLUMBING
J 2
(-7725 4925);
DISPLAY 0.872340 (-7725 4925);
PAINT GREEN (-7725 4925);
DISPLAY INVISIBLE (-7725 4925);
FORCEPROP 1 LAST HDL_TAP TRUE
J 2
(-8050 4750);
DISPLAY 0.872340 (-8050 4750);
DISPLAY INVISIBLE (-8050 4750);
FORCEPROP 1 LAST PATH I85
J 2
(-7723 4875);
DISPLAY 0.872340 (-7723 4875);
PAINT GREEN (-7723 4875);
DISPLAY INVISIBLE (-7723 4875);
FORCEADD TAP..1
R 2
(-7725 4825);
FORCEPROP 3 LASTPIN (-7675 4825) SIG_NAME M_K_CPU0_SB_CA<3>
J 0
(-7665 4835);
DISPLAY 0.659574 (-7665 4835);
PAINT MONO (-7665 4835);
DISPLAY INVISIBLE (-7665 4835);
FORCEPROP 1 LASTPIN (-7675 4825) BN 3
J 2
(-7663 4833);
DISPLAY 0.489362 (-7663 4833);
PAINT GREEN (-7663 4833);
FORCEPROP 2 LAST CDS_LIB mstr_standard
J 0
(-7725 4825);
DISPLAY 0.723404 (-7725 4825);
PAINT MONO (-7725 4825);
DISPLAY INVISIBLE (-7725 4825);
FORCEPROP 1 LAST BODY_TYPE PLUMBING
J 2
(-7725 4875);
DISPLAY 0.872340 (-7725 4875);
PAINT GREEN (-7725 4875);
DISPLAY INVISIBLE (-7725 4875);
FORCEPROP 1 LAST HDL_TAP TRUE
J 2
(-8050 4700);
DISPLAY 0.872340 (-8050 4700);
DISPLAY INVISIBLE (-8050 4700);
FORCEPROP 1 LAST PATH I86
J 2
(-7723 4825);
DISPLAY 0.872340 (-7723 4825);
PAINT GREEN (-7723 4825);
DISPLAY INVISIBLE (-7723 4825);
FORCEADD TAP..1
R 2
(-7725 4925);
FORCEPROP 3 LASTPIN (-7675 4925) SIG_NAME M_K_CPU0_SB_CA<5>
J 0
(-7665 4935);
DISPLAY 0.659574 (-7665 4935);
PAINT MONO (-7665 4935);
DISPLAY INVISIBLE (-7665 4935);
FORCEPROP 1 LASTPIN (-7675 4925) BN 5
J 2
(-7663 4933);
DISPLAY 0.489362 (-7663 4933);
PAINT GREEN (-7663 4933);
FORCEPROP 2 LAST CDS_LIB mstr_standard
J 0
(-7725 4925);
DISPLAY 0.723404 (-7725 4925);
PAINT MONO (-7725 4925);
DISPLAY INVISIBLE (-7725 4925);
FORCEPROP 1 LAST BODY_TYPE PLUMBING
J 2
(-7725 4975);
DISPLAY 0.872340 (-7725 4975);
PAINT GREEN (-7725 4975);
DISPLAY INVISIBLE (-7725 4975);
FORCEPROP 1 LAST HDL_TAP TRUE
J 2
(-8050 4800);
DISPLAY 0.872340 (-8050 4800);
DISPLAY INVISIBLE (-8050 4800);
FORCEPROP 1 LAST PATH I87
J 2
(-7723 4925);
DISPLAY 0.872340 (-7723 4925);
PAINT GREEN (-7723 4925);
DISPLAY INVISIBLE (-7723 4925);
FORCEADD TAP..1
R 2
(-7725 4975);
FORCEPROP 3 LASTPIN (-7675 4975) SIG_NAME M_K_CPU0_SB_CA<6>
J 0
(-7665 4985);
DISPLAY 0.659574 (-7665 4985);
PAINT MONO (-7665 4985);
DISPLAY INVISIBLE (-7665 4985);
FORCEPROP 1 LASTPIN (-7675 4975) BN 6
J 2
(-7663 4983);
DISPLAY 0.489362 (-7663 4983);
PAINT GREEN (-7663 4983);
FORCEPROP 2 LAST CDS_LIB mstr_standard
J 0
(-7725 4975);
DISPLAY 0.723404 (-7725 4975);
PAINT MONO (-7725 4975);
DISPLAY INVISIBLE (-7725 4975);
FORCEPROP 1 LAST BODY_TYPE PLUMBING
J 2
(-7725 5025);
DISPLAY 0.872340 (-7725 5025);
PAINT GREEN (-7725 5025);
DISPLAY INVISIBLE (-7725 5025);
FORCEPROP 1 LAST HDL_TAP TRUE
J 2
(-8050 4850);
DISPLAY 0.872340 (-8050 4850);
DISPLAY INVISIBLE (-8050 4850);
FORCEPROP 1 LAST PATH I88
J 2
(-7723 4975);
DISPLAY 0.872340 (-7723 4975);
PAINT GREEN (-7723 4975);
DISPLAY INVISIBLE (-7723 4975);
FORCEADD TAP..1
R 2
(-7725 5075);
FORCEPROP 3 LASTPIN (-7675 5075) SIG_NAME M_K_CPU0_SA_CA<0>
J 0
(-7665 5085);
DISPLAY 0.659574 (-7665 5085);
PAINT MONO (-7665 5085);
DISPLAY INVISIBLE (-7665 5085);
FORCEPROP 1 LASTPIN (-7675 5075) BN 0
J 2
(-7663 5083);
DISPLAY 0.489362 (-7663 5083);
PAINT GREEN (-7663 5083);
FORCEPROP 2 LAST CDS_LIB mstr_standard
J 0
(-7725 5075);
DISPLAY 0.723404 (-7725 5075);
PAINT MONO (-7725 5075);
DISPLAY INVISIBLE (-7725 5075);
FORCEPROP 1 LAST BODY_TYPE PLUMBING
J 2
(-7725 5125);
DISPLAY 0.872340 (-7725 5125);
PAINT GREEN (-7725 5125);
DISPLAY INVISIBLE (-7725 5125);
FORCEPROP 1 LAST HDL_TAP TRUE
J 2
(-8050 4950);
DISPLAY 0.872340 (-8050 4950);
DISPLAY INVISIBLE (-8050 4950);
FORCEPROP 1 LAST PATH I89
J 2
(-7723 5075);
DISPLAY 0.872340 (-7723 5075);
PAINT GREEN (-7723 5075);
DISPLAY INVISIBLE (-7723 5075);
FORCEADD VCC_CORE..1
(-8500 3400);
FORCEPROP 3 LASTPIN (-8500 3350) SIG_NAME P3V3_AUX\g
J 0
(-8490 3360);
DISPLAY 0.659574 (-8490 3360);
PAINT MONO (-8490 3360);
DISPLAY INVISIBLE (-8490 3360);
FORCEPROP 1 LAST HDL_POWER P3V3_AUX
J 1
(-8500 3450);
DISPLAY 0.489362 (-8500 3450);
PAINT GREEN (-8500 3450);
FORCEPROP 2 LAST CDS_LIB mstr_symbols
J 0
(-8500 3400);
PAINT MONO (-8500 3400);
DISPLAY INVISIBLE (-8500 3400);
FORCEPROP 0 LAST VOLTAGE 3.3
J 0
(-8775 3550);
DISPLAY 1.021277 (-8775 3550);
PAINT SKYBLUE (-8775 3550);
DISPLAY INVISIBLE (-8775 3550);
FORCEPROP 2 LAST ROOM PVCCINFAON_CPU0_CTRL
J 0
(-8500 3500);
DISPLAY 0.808511 (-8500 3500);
PAINT RED (-8500 3500);
DISPLAY INVISIBLE (-8500 3500);
FORCEPROP 1 LAST PATH I9
J 0
(-8450 3425);
DISPLAY 0.872340 (-8450 3425);
PAINT AQUA (-8450 3425);
DISPLAY INVISIBLE (-8450 3425);
FORCEADD TAP..1
R 2
(-7725 5125);
FORCEPROP 3 LASTPIN (-7675 5125) SIG_NAME M_K_CPU0_SA_CA<1>
J 0
(-7665 5135);
DISPLAY 0.659574 (-7665 5135);
PAINT MONO (-7665 5135);
DISPLAY INVISIBLE (-7665 5135);
FORCEPROP 1 LASTPIN (-7675 5125) BN 1
J 2
(-7663 5133);
DISPLAY 0.489362 (-7663 5133);
PAINT GREEN (-7663 5133);
FORCEPROP 2 LAST CDS_LIB mstr_standard
J 0
(-7725 5125);
DISPLAY 0.723404 (-7725 5125);
PAINT MONO (-7725 5125);
DISPLAY INVISIBLE (-7725 5125);
FORCEPROP 1 LAST BODY_TYPE PLUMBING
J 2
(-7725 5175);
DISPLAY 0.872340 (-7725 5175);
PAINT GREEN (-7725 5175);
DISPLAY INVISIBLE (-7725 5175);
FORCEPROP 1 LAST HDL_TAP TRUE
J 2
(-8050 5000);
DISPLAY 0.872340 (-8050 5000);
DISPLAY INVISIBLE (-8050 5000);
FORCEPROP 1 LAST PATH I90
J 2
(-7723 5125);
DISPLAY 0.872340 (-7723 5125);
PAINT GREEN (-7723 5125);
DISPLAY INVISIBLE (-7723 5125);
FORCEADD TAP..1
R 2
(-7725 5175);
FORCEPROP 3 LASTPIN (-7675 5175) SIG_NAME M_K_CPU0_SA_CA<2>
J 0
(-7665 5185);
DISPLAY 0.659574 (-7665 5185);
PAINT MONO (-7665 5185);
DISPLAY INVISIBLE (-7665 5185);
FORCEPROP 1 LASTPIN (-7675 5175) BN 2
J 2
(-7663 5183);
DISPLAY 0.489362 (-7663 5183);
PAINT GREEN (-7663 5183);
FORCEPROP 2 LAST CDS_LIB mstr_standard
J 0
(-7725 5175);
DISPLAY 0.723404 (-7725 5175);
PAINT MONO (-7725 5175);
DISPLAY INVISIBLE (-7725 5175);
FORCEPROP 1 LAST BODY_TYPE PLUMBING
J 2
(-7725 5225);
DISPLAY 0.872340 (-7725 5225);
PAINT GREEN (-7725 5225);
DISPLAY INVISIBLE (-7725 5225);
FORCEPROP 1 LAST HDL_TAP TRUE
J 2
(-8050 5050);
DISPLAY 0.872340 (-8050 5050);
DISPLAY INVISIBLE (-8050 5050);
FORCEPROP 1 LAST PATH I91
J 2
(-7723 5175);
DISPLAY 0.872340 (-7723 5175);
PAINT GREEN (-7723 5175);
DISPLAY INVISIBLE (-7723 5175);
FORCEADD TAP..1
R 2
(-7725 5225);
FORCEPROP 3 LASTPIN (-7675 5225) SIG_NAME M_K_CPU0_SA_CA<3>
J 0
(-7665 5235);
DISPLAY 0.659574 (-7665 5235);
PAINT MONO (-7665 5235);
DISPLAY INVISIBLE (-7665 5235);
FORCEPROP 1 LASTPIN (-7675 5225) BN 3
J 2
(-7663 5233);
DISPLAY 0.489362 (-7663 5233);
PAINT GREEN (-7663 5233);
FORCEPROP 2 LAST CDS_LIB mstr_standard
J 0
(-7725 5225);
DISPLAY 0.723404 (-7725 5225);
PAINT MONO (-7725 5225);
DISPLAY INVISIBLE (-7725 5225);
FORCEPROP 1 LAST BODY_TYPE PLUMBING
J 2
(-7725 5275);
DISPLAY 0.872340 (-7725 5275);
PAINT GREEN (-7725 5275);
DISPLAY INVISIBLE (-7725 5275);
FORCEPROP 1 LAST HDL_TAP TRUE
J 2
(-8050 5100);
DISPLAY 0.872340 (-8050 5100);
DISPLAY INVISIBLE (-8050 5100);
FORCEPROP 1 LAST PATH I92
J 2
(-7723 5225);
DISPLAY 0.872340 (-7723 5225);
PAINT GREEN (-7723 5225);
DISPLAY INVISIBLE (-7723 5225);
FORCEADD TAP..1
R 2
(-7725 5275);
FORCEPROP 3 LASTPIN (-7675 5275) SIG_NAME M_K_CPU0_SA_CA<4>
J 0
(-7665 5285);
DISPLAY 0.659574 (-7665 5285);
PAINT MONO (-7665 5285);
DISPLAY INVISIBLE (-7665 5285);
FORCEPROP 1 LASTPIN (-7675 5275) BN 4
J 2
(-7663 5283);
DISPLAY 0.489362 (-7663 5283);
PAINT GREEN (-7663 5283);
FORCEPROP 2 LAST CDS_LIB mstr_standard
J 0
(-7725 5275);
DISPLAY 0.723404 (-7725 5275);
PAINT MONO (-7725 5275);
DISPLAY INVISIBLE (-7725 5275);
FORCEPROP 1 LAST BODY_TYPE PLUMBING
J 2
(-7725 5325);
DISPLAY 0.872340 (-7725 5325);
PAINT GREEN (-7725 5325);
DISPLAY INVISIBLE (-7725 5325);
FORCEPROP 1 LAST HDL_TAP TRUE
J 2
(-8050 5150);
DISPLAY 0.872340 (-8050 5150);
DISPLAY INVISIBLE (-8050 5150);
FORCEPROP 1 LAST PATH I93
J 2
(-7723 5275);
DISPLAY 0.872340 (-7723 5275);
PAINT GREEN (-7723 5275);
DISPLAY INVISIBLE (-7723 5275);
FORCEADD TAP..1
R 2
(-7725 5325);
FORCEPROP 3 LASTPIN (-7675 5325) SIG_NAME M_K_CPU0_SA_CA<5>
J 0
(-7665 5335);
DISPLAY 0.659574 (-7665 5335);
PAINT MONO (-7665 5335);
DISPLAY INVISIBLE (-7665 5335);
FORCEPROP 1 LASTPIN (-7675 5325) BN 5
J 2
(-7663 5333);
DISPLAY 0.489362 (-7663 5333);
PAINT GREEN (-7663 5333);
FORCEPROP 2 LAST CDS_LIB mstr_standard
J 0
(-7725 5325);
DISPLAY 0.723404 (-7725 5325);
PAINT MONO (-7725 5325);
DISPLAY INVISIBLE (-7725 5325);
FORCEPROP 1 LAST BODY_TYPE PLUMBING
J 2
(-7725 5375);
DISPLAY 0.872340 (-7725 5375);
PAINT GREEN (-7725 5375);
DISPLAY INVISIBLE (-7725 5375);
FORCEPROP 1 LAST HDL_TAP TRUE
J 2
(-8050 5200);
DISPLAY 0.872340 (-8050 5200);
DISPLAY INVISIBLE (-8050 5200);
FORCEPROP 1 LAST PATH I94
J 2
(-7723 5325);
DISPLAY 0.872340 (-7723 5325);
PAINT GREEN (-7723 5325);
DISPLAY INVISIBLE (-7723 5325);
FORCEADD TAP..1
R 2
(-7725 5375);
FORCEPROP 3 LASTPIN (-7675 5375) SIG_NAME M_K_CPU0_SA_CA<6>
J 0
(-7665 5385);
DISPLAY 0.659574 (-7665 5385);
PAINT MONO (-7665 5385);
DISPLAY INVISIBLE (-7665 5385);
FORCEPROP 1 LASTPIN (-7675 5375) BN 6
J 2
(-7663 5383);
DISPLAY 0.489362 (-7663 5383);
PAINT GREEN (-7663 5383);
FORCEPROP 2 LAST CDS_LIB mstr_standard
J 0
(-7725 5375);
DISPLAY 0.723404 (-7725 5375);
PAINT MONO (-7725 5375);
DISPLAY INVISIBLE (-7725 5375);
FORCEPROP 1 LAST BODY_TYPE PLUMBING
J 2
(-7725 5425);
DISPLAY 0.872340 (-7725 5425);
PAINT GREEN (-7725 5425);
DISPLAY INVISIBLE (-7725 5425);
FORCEPROP 1 LAST HDL_TAP TRUE
J 2
(-8050 5250);
DISPLAY 0.872340 (-8050 5250);
DISPLAY INVISIBLE (-8050 5250);
FORCEPROP 1 LAST PATH I95
J 2
(-7723 5375);
DISPLAY 0.872340 (-7723 5375);
PAINT GREEN (-7723 5375);
DISPLAY INVISIBLE (-7723 5375);
FORCEADD TAP..1
(-6025 3925);
FORCEPROP 3 LASTPIN (-6075 3925) SIG_NAME M_K_CPU0_SA_DQ<2>
J 0
(-6065 3935);
DISPLAY 0.659574 (-6065 3935);
PAINT MONO (-6065 3935);
DISPLAY INVISIBLE (-6065 3935);
FORCEPROP 1 LASTPIN (-6075 3925) BN 2
J 0
(-6087 3933);
DISPLAY 0.489362 (-6087 3933);
PAINT GREEN (-6087 3933);
FORCEPROP 2 LAST CDS_LIB mstr_standard
J 0
(-6025 3925);
DISPLAY 0.723404 (-6025 3925);
PAINT MONO (-6025 3925);
DISPLAY INVISIBLE (-6025 3925);
FORCEPROP 1 LAST BODY_TYPE PLUMBING
J 0
(-6025 3975);
DISPLAY 0.872340 (-6025 3975);
PAINT GREEN (-6025 3975);
DISPLAY INVISIBLE (-6025 3975);
FORCEPROP 1 LAST HDL_TAP TRUE
J 0
(-5700 3800);
DISPLAY 0.872340 (-5700 3800);
DISPLAY INVISIBLE (-5700 3800);
FORCEPROP 1 LAST PATH I96
J 0
(-6027 3925);
DISPLAY 0.872340 (-6027 3925);
PAINT GREEN (-6027 3925);
DISPLAY INVISIBLE (-6027 3925);
FORCEADD TAP..1
(-6025 3975);
FORCEPROP 3 LASTPIN (-6075 3975) SIG_NAME M_K_CPU0_SA_DQ<3>
J 0
(-6065 3985);
DISPLAY 0.659574 (-6065 3985);
PAINT MONO (-6065 3985);
DISPLAY INVISIBLE (-6065 3985);
FORCEPROP 1 LASTPIN (-6075 3975) BN 3
J 0
(-6087 3983);
DISPLAY 0.489362 (-6087 3983);
PAINT GREEN (-6087 3983);
FORCEPROP 2 LAST CDS_LIB mstr_standard
J 0
(-6025 3975);
DISPLAY 0.723404 (-6025 3975);
PAINT MONO (-6025 3975);
DISPLAY INVISIBLE (-6025 3975);
FORCEPROP 1 LAST BODY_TYPE PLUMBING
J 0
(-6025 4025);
DISPLAY 0.872340 (-6025 4025);
PAINT GREEN (-6025 4025);
DISPLAY INVISIBLE (-6025 4025);
FORCEPROP 1 LAST HDL_TAP TRUE
J 0
(-5700 3850);
DISPLAY 0.872340 (-5700 3850);
DISPLAY INVISIBLE (-5700 3850);
FORCEPROP 1 LAST PATH I97
J 0
(-6027 3975);
DISPLAY 0.872340 (-6027 3975);
PAINT GREEN (-6027 3975);
DISPLAY INVISIBLE (-6027 3975);
FORCEADD TAP..1
(-6025 4025);
FORCEPROP 3 LASTPIN (-6075 4025) SIG_NAME M_K_CPU0_SA_DQ<4>
J 0
(-6065 4035);
DISPLAY 0.659574 (-6065 4035);
PAINT MONO (-6065 4035);
DISPLAY INVISIBLE (-6065 4035);
FORCEPROP 1 LASTPIN (-6075 4025) BN 4
J 0
(-6087 4033);
DISPLAY 0.489362 (-6087 4033);
PAINT GREEN (-6087 4033);
FORCEPROP 2 LAST CDS_LIB mstr_standard
J 0
(-6025 4025);
DISPLAY 0.723404 (-6025 4025);
PAINT MONO (-6025 4025);
DISPLAY INVISIBLE (-6025 4025);
FORCEPROP 1 LAST BODY_TYPE PLUMBING
J 0
(-6025 4075);
DISPLAY 0.872340 (-6025 4075);
PAINT GREEN (-6025 4075);
DISPLAY INVISIBLE (-6025 4075);
FORCEPROP 1 LAST HDL_TAP TRUE
J 0
(-5700 3900);
DISPLAY 0.872340 (-5700 3900);
DISPLAY INVISIBLE (-5700 3900);
FORCEPROP 1 LAST PATH I98
J 0
(-6027 4025);
DISPLAY 0.872340 (-6027 4025);
PAINT GREEN (-6027 4025);
DISPLAY INVISIBLE (-6027 4025);
FORCEADD TAP..1
(-6025 4075);
FORCEPROP 3 LASTPIN (-6075 4075) SIG_NAME M_K_CPU0_SA_DQ<5>
J 0
(-6065 4085);
DISPLAY 0.659574 (-6065 4085);
PAINT MONO (-6065 4085);
DISPLAY INVISIBLE (-6065 4085);
FORCEPROP 1 LASTPIN (-6075 4075) BN 5
J 0
(-6087 4083);
DISPLAY 0.489362 (-6087 4083);
PAINT GREEN (-6087 4083);
FORCEPROP 2 LAST CDS_LIB mstr_standard
J 0
(-6025 4075);
DISPLAY 0.723404 (-6025 4075);
PAINT MONO (-6025 4075);
DISPLAY INVISIBLE (-6025 4075);
FORCEPROP 1 LAST BODY_TYPE PLUMBING
J 0
(-6025 4125);
DISPLAY 0.872340 (-6025 4125);
PAINT GREEN (-6025 4125);
DISPLAY INVISIBLE (-6025 4125);
FORCEPROP 1 LAST HDL_TAP TRUE
J 0
(-5700 3950);
DISPLAY 0.872340 (-5700 3950);
DISPLAY INVISIBLE (-5700 3950);
FORCEPROP 1 LAST PATH I99
J 0
(-6027 4075);
DISPLAY 0.872340 (-6027 4075);
PAINT GREEN (-6027 4075);
DISPLAY INVISIBLE (-6027 4075);
FORCEADD DNS..2
(-8325 2275);
PAINT RED (-8325 2275);
FORCEPROP 2 LAST CDS_LIB mstr_misc
J 0
(-8325 2275);
DISPLAY INVISIBLE (-8325 2275);
FORCEPROP 1 LAST COMMENT_BODY TRUE
R 1
J 0
(-8250 2050);
DISPLAY 0.872340 (-8250 2050);
PAINT PEACH (-8250 2050);
DISPLAY INVISIBLE (-8250 2050);
FORCEADD QUANTA_TITLE_BLOCK_C..1
(0 0);
FORCEPROP 0 LAST CDS_CON_LAST_MODIFIED Thu Sep 14 16:12:09 2023
J 0
(-1885 15);
DISPLAY INVISIBLE (-1885 15);
FORCEPROP 1 LAST CUSTOM_TXT_CDS <CON_LAST_MODIFIED>
J 0
(-1885 15);
DISPLAY 0.978723 (-1885 15);
FORCEPROP 2 LAST CUSTOM_TXT_CDS <XR_PAGE_TITLE>
J 0
(-7890 5250);
DISPLAY 0.638298 (-7890 5250);
PAINT PINK (-7890 5250);
DISPLAY INVISIBLE (-7890 5250);
FORCEPROP 1 LAST CUSTOM_TXT_CDS <NAME_2>
J 0
(-3175 50);
FORCEPROP 1 LAST CUSTOM_TXT_CDS <NAME_1>
J 0
(-3175 175);
FORCEPROP 1 LAST CUSTOM_TXT_CDS <Q_NUMBER>
J 0
(-1403 103);
DISPLAY 1.212766 (-1403 103);
FORCEPROP 1 LAST CUSTOM_TXT_CDS <Q_PROJ>
J 0
(-2382 102);
DISPLAY 1.212766 (-2382 102);
FORCEPROP 1 LAST CUSTOM_TXT_CDS <Q_REV>
J 0
(-184 103);
DISPLAY 1.212766 (-184 103);
FORCEPROP 1 LAST CUSTOM_TXT_CDS <CON_PAGE_NUM> OF <CON_TOTAL_PAGES>
J 0
(-446 18);
DISPLAY 0.978723 (-446 18);
FORCEPROP 1 LAST Q_TITLE DDR5 - CPU0 CHK
J 0
(-9366 26);
DISPLAY 2.446809 (-9366 26);
PAINT GREEN (-9366 26);
FORCEPROP 2 LAST PAGE_BORDER TRUE
J 0
(-7890 5250);
DISPLAY 0.638298 (-7890 5250);
PAINT PINK (-7890 5250);
DISPLAY INVISIBLE (-7890 5250);
FORCEPROP 1 LAST CDS_LMAN_SYM_OUTLINE -9475,6775,100,-125
J 0
(0 0);
DISPLAY 0.468085 (0 0);
PAINT GREEN (0 0);
DISPLAY INVISIBLE (0 0);
FORCEPROP 2 LAST CDS_LIB pure_quanta
J 0
(0 0);
DISPLAY INVISIBLE (0 0);
FORCEPROP 2 LAST CDS_XR_PAGE_TITLE CR-96 : @T6G_MB_LIB.T6G(SCH_1):PAGE96
J 0
(-7890 5250);
DISPLAY 0.638298 (-7890 5250);
PAINT PINK (-7890 5250);
DISPLAY INVISIBLE (-7890 5250);
FORCEPROP 1 LAST Q_DEPT BU9
J 1
(-3763 49);
DISPLAY 1.957447 (-3763 49);
PAINT GREEN (-3763 49);
DISPLAY INVISIBLE (-3763 49);
FORCEPROP 1 LAST COMMENT_BODY TRUE
J 0
(12 -13);
DISPLAY 0.978723 (12 -13);
PAINT GREEN (12 -13);
DISPLAY INVISIBLE (12 -13);
WIRE 17 -1 (-7775 5350)(-7775 5400);
WIRE 17 -1 (-7775 5300)(-7775 5350);
WIRE 17 -1 (-7775 5400)(-7775 5425);
WIRE 17 -1 (-7775 5425)(-8275 5425);
FORCEPROP 2 LAST SIG_NAME M_K_CPU0_SA_CA<6:0>
J 0
(-8260 5435);
DISPLAY 0.489362 (-8260 5435);
WIRE 17 -1 (-7775 5250)(-7775 5300);
WIRE 17 -1 (-7775 5200)(-7775 5250);
WIRE 17 -1 (-7775 5150)(-7775 5200);
WIRE 17 -1 (-7775 5100)(-7775 5150);
WIRE 17 -1 (-3425 3600)(-3425 3575);
WIRE 17 -1 (-3425 3600)(-2525 3600);
FORCEPROP 2 LAST SIG_NAME M_K_CPU0_SB_DQS_DP<9:0>
J 0
(-3160 3610);
DISPLAY 0.489362 (-3160 3610);
WIRE 17 -1 (-3225 3550)(-3225 3525);
WIRE 17 -1 (-3225 3550)(-2525 3550);
FORCEPROP 2 LAST SIG_NAME M_K_CPU0_SB_DQS_DN<9:0>
J 0
(-3160 3560);
DISPLAY 0.489362 (-3160 3560);
WIRE 17 -1 (-3425 4650)(-3425 4625);
WIRE 17 -1 (-3425 4650)(-2525 4650);
FORCEPROP 2 LAST SIG_NAME M_K_CPU0_SA_DQS_DP<9:0>
J 0
(-3160 4660);
DISPLAY 0.489362 (-3160 4660);
WIRE 17 -1 (-3225 4600)(-3225 4575);
WIRE 17 -1 (-3225 4600)(-2525 4600);
FORCEPROP 2 LAST SIG_NAME M_K_CPU0_SA_DQS_DN<9:0>
J 0
(-3160 4610);
DISPLAY 0.489362 (-3160 4610);
WIRE 17 -1 (-3425 4625)(-3425 4525);
WIRE 17 -1 (-3425 4525)(-3425 4425);
WIRE 17 -1 (-3425 4425)(-3425 4325);
WIRE 17 -1 (-3225 4575)(-3225 4475);
WIRE 17 -1 (-3225 4475)(-3225 4375);
WIRE 17 -1 (-3225 4375)(-3225 4275);
WIRE 17 -1 (-3225 3425)(-3225 3325);
WIRE 17 -1 (-3225 3525)(-3225 3425);
WIRE 17 -1 (-3225 3325)(-3225 3225);
WIRE 17 -1 (-3225 3225)(-3225 3125);
WIRE 17 -1 (-3425 4325)(-3425 4225);
WIRE 17 -1 (-3425 3375)(-3425 3275);
WIRE 17 -1 (-3425 3475)(-3425 3375);
WIRE 17 -1 (-3425 3275)(-3425 3175);
WIRE 17 -1 (-3425 3075)(-3425 3175);
WIRE 17 -1 (-3425 3575)(-3425 3475);
WIRE 17 -1 (-3425 2975)(-3425 3075);
WIRE 17 -1 (-3425 2875)(-3425 2975);
WIRE 17 -1 (-3225 3025)(-3225 3125);
WIRE 17 -1 (-3225 2925)(-3225 3025);
WIRE 17 -1 (-3225 2825)(-3225 2925);
WIRE 17 -1 (-3225 4275)(-3225 4175);
WIRE 17 -1 (-3225 4075)(-3225 4175);
WIRE 17 -1 (-3225 3975)(-3225 4075);
WIRE 17 -1 (-3225 3875)(-3225 3975);
WIRE 17 -1 (-3425 2875)(-3425 2775);
WIRE 17 -1 (-3225 2825)(-3225 2725);
WIRE 17 -1 (-3425 4125)(-3425 4225);
WIRE 17 -1 (-3425 4025)(-3425 4125);
WIRE 17 -1 (-3425 3925)(-3425 4025);
WIRE 17 -1 (-3425 3925)(-3425 3825);
WIRE 17 -1 (-3225 3875)(-3225 3775);
WIRE 17 -1 (-3425 2775)(-3425 2675);
WIRE 17 -1 (-3225 2725)(-3225 2625);
WIRE 17 -1 (-3425 3825)(-3425 3725);
WIRE 17 -1 (-3225 3775)(-3225 3675);
WIRE 17 -1 (-5975 2200)(-5975 2250);
WIRE 17 -1 (-5975 2250)(-5975 2300);
WIRE 17 -1 (-5975 2300)(-5975 2350);
WIRE 17 -1 (-5975 2350)(-5975 2400);
WIRE 17 -1 (-5975 2450)(-5975 2400);
WIRE 17 -1 (-5975 2500)(-5975 2450);
WIRE 17 -1 (-5975 2550)(-5975 2500);
WIRE 17 -1 (-5975 2600)(-5975 2550);
WIRE 17 -1 (-5975 2650)(-5975 2600);
WIRE 17 -1 (-5975 2700)(-5975 2650);
WIRE 17 -1 (-5975 2750)(-5975 2700);
WIRE 17 -1 (-5975 2800)(-5975 2750);
WIRE 17 -1 (-5975 2800)(-5975 2850);
WIRE 17 -1 (-5975 2850)(-5975 2900);
WIRE 17 -1 (-5975 2900)(-5975 2950);
WIRE 17 -1 (-5975 2950)(-5975 3000);
WIRE 17 -1 (-5975 3050)(-5975 3000);
WIRE 17 -1 (-5975 3100)(-5975 3050);
WIRE 17 -1 (-5975 3150)(-5975 3100);
WIRE 17 -1 (-5975 3200)(-5975 3150);
WIRE 17 -1 (-5975 3250)(-5975 3200);
WIRE 17 -1 (-5975 3300)(-5975 3250);
WIRE 17 -1 (-5975 3350)(-5975 3300);
WIRE 17 -1 (-5975 3400)(-5975 3350);
WIRE 17 -1 (-5975 3450)(-5975 3400);
WIRE 17 -1 (-5975 3500)(-5975 3450);
WIRE 17 -1 (-5975 3550)(-5975 3500);
WIRE 17 -1 (-5975 3600)(-5975 3550);
WIRE 17 -1 (-5975 3650)(-5975 3600);
WIRE 17 -1 (-5975 3700)(-5975 3650);
WIRE 17 -1 (-5975 3750)(-5975 3700);
WIRE 17 -1 (-5975 3775)(-5975 3750);
WIRE 17 -1 (-5975 3775)(-5400 3775);
FORCEPROP 2 LAST SIG_NAME M_K_CPU0_SB_DQ<31:0>
J 0
(-5910 3785);
DISPLAY 0.489362 (-5910 3785);
WIRE 17 -1 (-5975 3850)(-5975 3900);
WIRE 17 -1 (-5975 3900)(-5975 3950);
WIRE 17 -1 (-5975 3950)(-5975 4000);
WIRE 17 -1 (-5975 4000)(-5975 4050);
WIRE 17 -1 (-5975 4100)(-5975 4050);
WIRE 17 -1 (-5975 4150)(-5975 4100);
WIRE 17 -1 (-5975 4200)(-5975 4150);
WIRE 17 -1 (-5975 4250)(-5975 4200);
WIRE 17 -1 (-5975 4300)(-5975 4250);
WIRE 17 -1 (-5975 4350)(-5975 4300);
WIRE 17 -1 (-5975 4400)(-5975 4350);
WIRE 17 -1 (-5975 4450)(-5975 4400);
WIRE 17 -1 (-5975 4450)(-5975 4500);
WIRE 17 -1 (-5975 4500)(-5975 4550);
WIRE 17 -1 (-5975 4550)(-5975 4600);
WIRE 17 -1 (-5975 4600)(-5975 4650);
WIRE 17 -1 (-5975 4700)(-5975 4650);
WIRE 17 -1 (-5975 4750)(-5975 4700);
WIRE 17 -1 (-5975 4800)(-5975 4750);
WIRE 17 -1 (-5975 4850)(-5975 4800);
WIRE 17 -1 (-5975 4900)(-5975 4850);
WIRE 17 -1 (-5975 4950)(-5975 4900);
WIRE 17 -1 (-5975 5000)(-5975 4950);
WIRE 17 -1 (-5975 5050)(-5975 5000);
WIRE 17 -1 (-5975 5100)(-5975 5050);
WIRE 17 -1 (-5975 5150)(-5975 5100);
WIRE 17 -1 (-5975 5200)(-5975 5150);
WIRE 17 -1 (-5975 5250)(-5975 5200);
WIRE 17 -1 (-5975 5300)(-5975 5250);
WIRE 17 -1 (-5975 5350)(-5975 5300);
WIRE 17 -1 (-5975 5400)(-5975 5350);
WIRE 17 -1 (-5975 5425)(-5975 5400);
WIRE 17 -1 (-5975 5425)(-5400 5425);
FORCEPROP 2 LAST SIG_NAME M_K_CPU0_SA_DQ<31:0>
J 0
(-5910 5435);
DISPLAY 0.489362 (-5910 5435);
WIRE 17 -1 (-7775 3300)(-7775 3350);
WIRE 17 -1 (-7775 3250)(-7775 3300);
WIRE 17 -1 (-7775 3350)(-7775 3400);
WIRE 17 -1 (-7775 3450)(-7775 3400);
WIRE 17 -1 (-7775 3200)(-7775 3250);
WIRE 17 -1 (-7775 3450)(-7775 3500);
WIRE 17 -1 (-7775 3550)(-7775 3500);
WIRE 17 -1 (-7775 3550)(-7775 3575);
WIRE 17 -1 (-7775 3575)(-8275 3575);
FORCEPROP 2 LAST SIG_NAME M_K_CPU0_SB_CB<7:0>
J 0
(-8225 3585);
DISPLAY 0.489362 (-8225 3585);
WIRE 17 -1 (-7775 3700)(-7775 3750);
WIRE 17 -1 (-7775 3650)(-7775 3700);
WIRE 17 -1 (-7775 3750)(-7775 3800);
WIRE 17 -1 (-7775 3800)(-7775 3850);
WIRE 17 -1 (-7775 3900)(-7775 3850);
WIRE 17 -1 (-7775 3900)(-7775 3950);
WIRE 17 -1 (-7775 4000)(-7775 3950);
WIRE 17 -1 (-7775 4000)(-7775 4025);
WIRE 17 -1 (-7775 4025)(-8275 4025);
FORCEPROP 2 LAST SIG_NAME M_K_CPU0_SA_CB<7:0>
J 0
(-8225 4035);
DISPLAY 0.489362 (-8225 4035);
WIRE 17 -1 (-7775 4950)(-7775 5000);
WIRE 17 -1 (-7775 4900)(-7775 4950);
WIRE 17 -1 (-7775 5000)(-7775 5025);
WIRE 17 -1 (-7775 5025)(-8275 5025);
FORCEPROP 2 LAST SIG_NAME M_K_CPU0_SB_CA<6:0>
J 0
(-8260 5035);
DISPLAY 0.489362 (-8260 5035);
WIRE 17 -1 (-7775 4850)(-7775 4900);
WIRE 17 -1 (-7775 4800)(-7775 4850);
WIRE 17 -1 (-7775 4750)(-7775 4800);
WIRE 17 -1 (-7775 4700)(-7775 4750);
WIRE 16 -1 (-6425 1100)(-6425 1175);
WIRE 16 -1 (-8600 3025)(-8600 3100);
WIRE 16 -1 (-8350 2375)(-8350 2400);
WIRE 16 -1 (-7475 3275)(-7675 3275);
WIRE 16 -1 (-8500 2925)(-7475 2925);
WIRE 16 -1 (-8500 3325)(-8500 2925);
WIRE 16 -1 (-8500 3350)(-8500 3325);
WIRE 16 -1 (-8600 3325)(-8500 3325);
WIRE 16 -1 (-8600 3300)(-8600 3325);
WIRE 16 -1 (-7875 2600)(-8375 2600);
FORCEPROP 2 LAST SIG_NAME I3C_SPD_DDRGL_CPU0_SCL
J 0
(-8435 2610);
DISPLAY 0.489362 (-8435 2610);
WIRE 16 -1 (-8300 2825)(-8275 2825);
WIRE 16 -1 (-8300 2700)(-8300 2825);
WIRE 16 -1 (-8300 2700)(-8800 2700);
FORCEPROP 2 LAST SIG_NAME I3C_SPD_DDRGL_CPU0_SDA
J 0
(-8810 2710);
DISPLAY 0.489362 (-8810 2710);
WIRE 16 -1 (-7475 2825)(-8075 2825);
FORCEPROP 2 LAST SIG_NAME I3C_SPD_DDRK_CPU0_SDA
J 0
(-8010 2835);
DISPLAY 0.446809 (-8010 2835);
FORCEPROP 2 LASTPROP $XRERR UNIQUE?
J 0
(-8250 2835);
DISPLAY 0.638298 (-8250 2835);
PAINT MONO (-8250 2835);
DISPLAY INVISIBLE (-8250 2835);
WIRE 16 -1 (-7575 2600)(-7675 2600);
WIRE 16 -1 (-7575 2775)(-7575 2600);
WIRE 16 -1 (-7475 2775)(-7575 2775);
FORCEPROP 2 LAST SIG_NAME I3C_SPD_DDRK_CPU0_SCL
J 0
(-7960 2785);
DISPLAY 0.446809 (-7960 2785);
FORCEPROP 2 LASTPROP $XRERR UNIQUE?
J 0
(-8200 2785);
DISPLAY 0.638298 (-8200 2785);
PAINT MONO (-8200 2785);
DISPLAY INVISIBLE (-8200 2785);
WIRE 16 -1 (-8350 2175)(-8350 2125);
WIRE 16 -1 (-8150 2125)(-8350 2125);
WIRE 16 -1 (-8350 2125)(-8375 2125);
WIRE 16 -1 (-8150 2125)(-8150 2525);
WIRE 16 -1 (-7475 2525)(-8150 2525);
FORCEPROP 2 LAST SIG_NAME PWRGD_CHK_CPU0_DIMM
J 0
(-8060 2535);
DISPLAY 0.489362 (-8060 2535);
FORCEPROP 2 LASTPROP $XRERR UNIQUE?
J 0
(-8300 2535);
DISPLAY 0.638298 (-8300 2535);
PAINT MONO (-8300 2535);
DISPLAY INVISIBLE (-8300 2535);
WIRE 16 -1 (-7475 2875)(-8425 2875);
FORCEPROP 2 LAST SIG_NAME PD_CHK_CPU0_DIMM_SAA
J 0
(-8400 2885);
DISPLAY 0.489362 (-8400 2885);
WIRE 16 -1 (-7475 3025)(-8100 3025);
FORCEPROP 2 LAST SIG_NAME M_K_CPU0_ALERT_N
J 0
(-8085 3035);
DISPLAY 0.489362 (-8085 3035);
WIRE 16 -1 (-7475 3075)(-8100 3075);
FORCEPROP 2 LAST SIG_NAME M_K_CPU0_RESET_N
J 0
(-8085 3085);
DISPLAY 0.489362 (-8085 3085);
WIRE 16 -1 (-6075 3425)(-6275 3425);
WIRE 16 -1 (-6275 3525)(-6075 3525);
WIRE 16 -1 (-1825 2125)(-2125 2125);
WIRE 16 -1 (-2125 2125)(-2125 2075);
WIRE 16 -1 (-2125 2175)(-2125 2125);
WIRE 16 -1 (-1825 2175)(-2125 2175);
WIRE 16 -1 (-2125 2225)(-2125 2175);
WIRE 16 -1 (-1825 2075)(-2125 2075);
WIRE 16 -1 (-2125 2075)(-2125 1950);
WIRE 16 -1 (-1825 2225)(-2125 2225);
WIRE 16 -1 (-2125 2275)(-2125 2225);
WIRE 16 -1 (-1825 2275)(-2125 2275);
WIRE 16 -1 (-2125 2325)(-2125 2275);
WIRE 16 -1 (-1825 2325)(-2125 2325);
WIRE 16 -1 (-2125 2375)(-2125 2325);
WIRE 16 -1 (-1825 2375)(-2125 2375);
WIRE 16 -1 (-2125 2425)(-2125 2375);
WIRE 16 -1 (-1825 2425)(-2125 2425);
WIRE 16 -1 (-2125 2475)(-2125 2425);
WIRE 16 -1 (-1825 2475)(-2125 2475);
WIRE 16 -1 (-2125 2525)(-2125 2475);
WIRE 16 -1 (-1825 2525)(-2125 2525);
WIRE 16 -1 (-2125 2575)(-2125 2525);
WIRE 16 -1 (-1825 2575)(-2125 2575);
WIRE 16 -1 (-2125 2625)(-2125 2575);
WIRE 16 -1 (-1825 2625)(-2125 2625);
WIRE 16 -1 (-2125 2675)(-2125 2625);
WIRE 16 -1 (-1825 2675)(-2125 2675);
WIRE 16 -1 (-2125 2725)(-2125 2675);
WIRE 16 -1 (-1825 2725)(-2125 2725);
WIRE 16 -1 (-2125 2775)(-2125 2725);
WIRE 16 -1 (-1825 2775)(-2125 2775);
WIRE 16 -1 (-2125 2825)(-2125 2775);
WIRE 16 -1 (-1825 2825)(-2125 2825);
WIRE 16 -1 (-2125 2875)(-2125 2825);
WIRE 16 -1 (-1825 2875)(-2125 2875);
WIRE 16 -1 (-2125 2925)(-2125 2875);
WIRE 16 -1 (-1825 2925)(-2125 2925);
WIRE 16 -1 (-2125 2975)(-2125 2925);
WIRE 16 -1 (-1825 2975)(-2125 2975);
WIRE 16 -1 (-2125 3025)(-2125 2975);
WIRE 16 -1 (-1825 3025)(-2125 3025);
WIRE 16 -1 (-2125 3075)(-2125 3025);
WIRE 16 -1 (-1825 3075)(-2125 3075);
WIRE 16 -1 (-2125 3125)(-2125 3075);
WIRE 16 -1 (-1825 3125)(-2125 3125);
WIRE 16 -1 (-2125 3175)(-2125 3125);
WIRE 16 -1 (-1825 3175)(-2125 3175);
WIRE 16 -1 (-2125 3225)(-2125 3175);
WIRE 16 -1 (-1825 3225)(-2125 3225);
WIRE 16 -1 (-2125 3275)(-2125 3225);
WIRE 16 -1 (-1825 3275)(-2125 3275);
WIRE 16 -1 (-2125 3325)(-2125 3275);
WIRE 16 -1 (-1825 3325)(-2125 3325);
WIRE 16 -1 (-2125 3375)(-2125 3325);
WIRE 16 -1 (-1825 3375)(-2125 3375);
WIRE 16 -1 (-2125 3425)(-2125 3375);
WIRE 16 -1 (-1825 3425)(-2125 3425);
WIRE 16 -1 (-2125 3475)(-2125 3425);
WIRE 16 -1 (-1825 3475)(-2125 3475);
WIRE 16 -1 (-2125 3525)(-2125 3475);
WIRE 16 -1 (-1825 3525)(-2125 3525);
WIRE 16 -1 (-2125 3575)(-2125 3525);
WIRE 16 -1 (-1825 3575)(-2125 3575);
WIRE 16 -1 (-2125 3625)(-2125 3575);
WIRE 16 -1 (-1825 3625)(-2125 3625);
WIRE 16 -1 (-2125 3675)(-2125 3625);
WIRE 16 -1 (-1825 3675)(-2125 3675);
WIRE 16 -1 (-2125 3725)(-2125 3675);
WIRE 16 -1 (-1825 3725)(-2125 3725);
WIRE 16 -1 (-2125 3775)(-2125 3725);
WIRE 16 -1 (-1825 3775)(-2125 3775);
WIRE 16 -1 (-2125 3825)(-2125 3775);
WIRE 16 -1 (-1825 3825)(-2125 3825);
WIRE 16 -1 (-2125 3875)(-2125 3825);
WIRE 16 -1 (-1825 3875)(-2125 3875);
WIRE 16 -1 (-2125 3925)(-2125 3875);
WIRE 16 -1 (-1825 3925)(-2125 3925);
WIRE 16 -1 (-2125 3975)(-2125 3925);
WIRE 16 -1 (-1825 3975)(-2125 3975);
WIRE 16 -1 (-2125 4025)(-2125 3975);
WIRE 16 -1 (-1825 4025)(-2125 4025);
WIRE 16 -1 (-2125 4075)(-2125 4025);
WIRE 16 -1 (-2125 4125)(-2125 4075);
WIRE 16 -1 (-1825 4075)(-2125 4075);
WIRE 16 -1 (-1825 4125)(-2125 4125);
WIRE 16 -1 (-2125 4175)(-2125 4125);
WIRE 16 -1 (-1825 4175)(-2125 4175);
WIRE 16 -1 (-2125 4225)(-2125 4175);
WIRE 16 -1 (-1825 4225)(-2125 4225);
WIRE 16 -1 (-2125 4275)(-2125 4225);
WIRE 16 -1 (-1825 4275)(-2125 4275);
WIRE 16 -1 (-2125 4325)(-2125 4275);
WIRE 16 -1 (-1825 4325)(-2125 4325);
WIRE 16 -1 (-2125 4375)(-2125 4325);
WIRE 16 -1 (-1825 4375)(-2125 4375);
WIRE 16 -1 (-2125 4425)(-2125 4375);
WIRE 16 -1 (-1825 4425)(-2125 4425);
WIRE 16 -1 (-2125 4475)(-2125 4425);
WIRE 16 -1 (-1825 4475)(-2125 4475);
WIRE 16 -1 (-2125 4525)(-2125 4475);
WIRE 16 -1 (-1825 4525)(-2125 4525);
WIRE 16 -1 (-2125 4575)(-2125 4525);
WIRE 16 -1 (-1825 4575)(-2125 4575);
WIRE 16 -1 (-2125 4625)(-2125 4575);
WIRE 16 -1 (-1825 4625)(-2125 4625);
WIRE 16 -1 (-2125 4675)(-2125 4625);
WIRE 16 -1 (-1825 4675)(-2125 4675);
WIRE 16 -1 (-2125 4725)(-2125 4675);
WIRE 16 -1 (-1825 4725)(-2125 4725);
WIRE 16 -1 (-2125 4775)(-2125 4725);
WIRE 16 -1 (-1825 4775)(-2125 4775);
WIRE 16 -1 (-2125 4825)(-2125 4775);
WIRE 16 -1 (-1825 4825)(-2125 4825);
WIRE 16 -1 (-2125 4875)(-2125 4825);
WIRE 16 -1 (-1825 4875)(-2125 4875);
WIRE 16 -1 (-2125 4925)(-2125 4875);
WIRE 16 -1 (-1825 4925)(-2125 4925);
WIRE 16 -1 (-2125 4975)(-2125 4925);
WIRE 16 -1 (-1825 4975)(-2125 4975);
WIRE 16 -1 (-2125 5025)(-2125 4975);
WIRE 16 -1 (-1825 5025)(-2125 5025);
WIRE 16 -1 (-2125 5075)(-2125 5025);
WIRE 16 -1 (-1825 5075)(-2125 5075);
WIRE 16 -1 (-2125 5125)(-2125 5075);
WIRE 16 -1 (-1825 5125)(-2125 5125);
WIRE 16 -1 (-2125 5175)(-2125 5125);
WIRE 16 -1 (-1825 5175)(-2125 5175);
WIRE 16 -1 (-325 2175)(-325 2075);
WIRE 16 -1 (-325 2225)(-325 2175);
WIRE 16 -1 (-325 2175)(-625 2175);
WIRE 16 -1 (-325 2075)(-625 2075);
WIRE 16 -1 (-325 2075)(-325 2025);
WIRE 16 -1 (-325 2025)(-325 1975);
WIRE 16 -1 (-325 2025)(-625 2025);
WIRE 16 -1 (-325 2275)(-325 2225);
WIRE 16 -1 (-325 2225)(-625 2225);
WIRE 16 -1 (-325 2325)(-325 2275);
WIRE 16 -1 (-325 2275)(-625 2275);
WIRE 16 -1 (-325 1975)(-325 1725);
WIRE 16 -1 (-325 1975)(-625 1975);
WIRE 16 -1 (-325 2375)(-325 2325);
WIRE 16 -1 (-325 2325)(-625 2325);
WIRE 16 -1 (-325 2425)(-325 2375);
WIRE 16 -1 (-325 2375)(-625 2375);
WIRE 16 -1 (-325 2475)(-325 2425);
WIRE 16 -1 (-325 2425)(-625 2425);
WIRE 16 -1 (-325 2525)(-325 2475);
WIRE 16 -1 (-325 2475)(-625 2475);
WIRE 16 -1 (-325 2575)(-325 2525);
WIRE 16 -1 (-325 2525)(-625 2525);
WIRE 16 -1 (-325 2625)(-325 2575);
WIRE 16 -1 (-325 2575)(-625 2575);
WIRE 16 -1 (-325 2675)(-325 2625);
WIRE 16 -1 (-325 2625)(-625 2625);
WIRE 16 -1 (-325 2725)(-325 2675);
WIRE 16 -1 (-325 2675)(-625 2675);
WIRE 16 -1 (-325 2775)(-325 2725);
WIRE 16 -1 (-325 2725)(-625 2725);
WIRE 16 -1 (-325 2825)(-325 2775);
WIRE 16 -1 (-325 2775)(-625 2775);
WIRE 16 -1 (-325 2875)(-325 2825);
WIRE 16 -1 (-325 2825)(-625 2825);
WIRE 16 -1 (-325 2925)(-325 2875);
WIRE 16 -1 (-325 2875)(-625 2875);
WIRE 16 -1 (-325 2975)(-325 2925);
WIRE 16 -1 (-325 2925)(-625 2925);
WIRE 16 -1 (-325 3025)(-325 2975);
WIRE 16 -1 (-325 2975)(-625 2975);
WIRE 16 -1 (-325 3075)(-325 3025);
WIRE 16 -1 (-325 3025)(-625 3025);
WIRE 16 -1 (-325 3125)(-325 3075);
WIRE 16 -1 (-325 3075)(-625 3075);
WIRE 16 -1 (-325 3175)(-325 3125);
WIRE 16 -1 (-325 3125)(-625 3125);
WIRE 16 -1 (-325 3225)(-325 3175);
WIRE 16 -1 (-325 3175)(-625 3175);
WIRE 16 -1 (-325 3275)(-325 3225);
WIRE 16 -1 (-325 3225)(-625 3225);
WIRE 16 -1 (-325 3325)(-325 3275);
WIRE 16 -1 (-325 3275)(-625 3275);
WIRE 16 -1 (-325 3375)(-325 3325);
WIRE 16 -1 (-325 3325)(-625 3325);
WIRE 16 -1 (-325 3425)(-325 3375);
WIRE 16 -1 (-325 3375)(-625 3375);
WIRE 16 -1 (-325 3475)(-325 3425);
WIRE 16 -1 (-325 3425)(-625 3425);
WIRE 16 -1 (-325 3525)(-325 3475);
WIRE 16 -1 (-325 3475)(-625 3475);
WIRE 16 -1 (-325 3575)(-325 3525);
WIRE 16 -1 (-325 3525)(-625 3525);
WIRE 16 -1 (-325 3625)(-325 3575);
WIRE 16 -1 (-325 3575)(-625 3575);
WIRE 16 -1 (-325 3675)(-325 3625);
WIRE 16 -1 (-325 3625)(-625 3625);
WIRE 16 -1 (-325 3725)(-325 3675);
WIRE 16 -1 (-325 3675)(-625 3675);
WIRE 16 -1 (-325 3775)(-325 3725);
WIRE 16 -1 (-325 3725)(-625 3725);
WIRE 16 -1 (-325 3825)(-325 3775);
WIRE 16 -1 (-325 3775)(-625 3775);
WIRE 16 -1 (-325 3875)(-325 3825);
WIRE 16 -1 (-325 3825)(-625 3825);
WIRE 16 -1 (-325 3925)(-325 3875);
WIRE 16 -1 (-325 3875)(-625 3875);
WIRE 16 -1 (-325 3975)(-325 3925);
WIRE 16 -1 (-325 3925)(-625 3925);
WIRE 16 -1 (-325 4025)(-325 3975);
WIRE 16 -1 (-325 3975)(-625 3975);
WIRE 16 -1 (-325 4075)(-325 4025);
WIRE 16 -1 (-325 4025)(-625 4025);
WIRE 16 -1 (-325 4125)(-325 4075);
WIRE 16 -1 (-325 4075)(-625 4075);
WIRE 16 -1 (-325 4175)(-325 4125);
WIRE 16 -1 (-325 4125)(-625 4125);
WIRE 16 -1 (-325 4225)(-325 4175);
WIRE 16 -1 (-325 4175)(-625 4175);
WIRE 16 -1 (-325 4275)(-325 4225);
WIRE 16 -1 (-325 4225)(-625 4225);
WIRE 16 -1 (-325 4325)(-325 4275);
WIRE 16 -1 (-325 4275)(-625 4275);
WIRE 16 -1 (-325 4375)(-325 4325);
WIRE 16 -1 (-325 4325)(-625 4325);
WIRE 16 -1 (-325 4425)(-325 4375);
WIRE 16 -1 (-325 4375)(-625 4375);
WIRE 16 -1 (-325 4475)(-325 4425);
WIRE 16 -1 (-325 4425)(-625 4425);
WIRE 16 -1 (-325 4525)(-325 4475);
WIRE 16 -1 (-325 4475)(-625 4475);
WIRE 16 -1 (-325 4575)(-325 4525);
WIRE 16 -1 (-325 4525)(-625 4525);
WIRE 16 -1 (-325 4625)(-325 4575);
WIRE 16 -1 (-325 4575)(-625 4575);
WIRE 16 -1 (-325 4675)(-325 4625);
WIRE 16 -1 (-325 4625)(-625 4625);
WIRE 16 -1 (-325 4725)(-325 4675);
WIRE 16 -1 (-325 4675)(-625 4675);
WIRE 16 -1 (-325 4775)(-325 4725);
WIRE 16 -1 (-325 4725)(-625 4725);
WIRE 16 -1 (-325 4825)(-325 4775);
WIRE 16 -1 (-325 4775)(-625 4775);
WIRE 16 -1 (-325 4875)(-325 4825);
WIRE 16 -1 (-325 4825)(-625 4825);
WIRE 16 -1 (-325 4925)(-325 4875);
WIRE 16 -1 (-325 4875)(-625 4875);
WIRE 16 -1 (-325 4975)(-325 4925);
WIRE 16 -1 (-325 4925)(-625 4925);
WIRE 16 -1 (-325 5025)(-325 4975);
WIRE 16 -1 (-325 4975)(-625 4975);
WIRE 16 -1 (-325 5075)(-325 5025);
WIRE 16 -1 (-325 5025)(-625 5025);
WIRE 16 -1 (-325 5125)(-325 5075);
WIRE 16 -1 (-325 5075)(-625 5075);
WIRE 16 -1 (-325 5175)(-325 5125);
WIRE 16 -1 (-325 5125)(-625 5125);
WIRE 16 -1 (-325 5225)(-325 5175);
WIRE 16 -1 (-325 5175)(-625 5175);
WIRE 16 -1 (-325 5275)(-325 5225);
WIRE 16 -1 (-325 5225)(-625 5225);
WIRE 16 -1 (-325 5325)(-325 5275);
WIRE 16 -1 (-325 5275)(-625 5275);
WIRE 16 -1 (-325 5325)(-625 5325);
WIRE 16 -1 (-2250 5775)(-2250 5900);
WIRE 16 -1 (-2250 5775)(-2825 5775);
WIRE 16 -1 (-2825 5775)(-2825 5900);
WIRE 16 -1 (-2825 5775)(-2825 5700);
WIRE 16 -1 (-2250 6200)(-2125 6200);
WIRE 16 -1 (-2250 6200)(-2825 6200);
WIRE 16 -1 (-2250 6200)(-2250 6100);
WIRE 16 -1 (-2125 5325)(-2125 6200);
WIRE 16 -1 (-1825 5325)(-2125 5325);
WIRE 16 -1 (-2125 5275)(-2125 5325);
WIRE 16 -1 (-2825 6100)(-2825 6200);
WIRE 16 -1 (-2825 6200)(-2825 6275);
WIRE 16 -1 (-1825 5275)(-2125 5275);
WIRE 16 -1 (-2125 5275)(-2125 5225);
WIRE 16 -1 (-2125 5225)(-1825 5225);
WIRE 16 -1 (-7475 3175)(-7675 3175);
WIRE 16 -1 (-7475 3225)(-7675 3225);
WIRE 16 -1 (-7475 3375)(-7675 3375);
WIRE 16 -1 (-7475 3425)(-7675 3425);
WIRE 16 -1 (-7475 3625)(-7675 3625);
WIRE 16 -1 (-6425 1450)(-6425 1375);
WIRE 16 -1 (-6425 1450)(-7150 1450);
FORCEPROP 2 LAST SIG_NAME PD_CHK_CPU0_DIMM_SAA
J 0
(-7135 1460);
DISPLAY 0.489362 (-7135 1460);
WIRE 16 -1 (-6275 5375)(-6075 5375);
WIRE 16 -1 (-7475 3975)(-7675 3975);
WIRE 16 -1 (-7475 3825)(-7675 3825);
WIRE 16 -1 (-7475 3675)(-7675 3675);
WIRE 16 -1 (-7475 3525)(-7675 3525);
WIRE 16 -1 (-7475 5075)(-7675 5075);
WIRE 16 -1 (-7475 4675)(-7675 4675);
WIRE 16 -1 (-7475 5125)(-7675 5125);
WIRE 16 -1 (-7475 4725)(-7675 4725);
WIRE 16 -1 (-7475 5175)(-7675 5175);
WIRE 16 -1 (-7475 4775)(-7675 4775);
WIRE 16 -1 (-7475 4825)(-7675 4825);
WIRE 16 -1 (-7475 4875)(-7675 4875);
WIRE 16 -1 (-7475 4925)(-7675 4925);
WIRE 16 -1 (-7475 4975)(-7675 4975);
WIRE 16 -1 (-7475 3925)(-7675 3925);
WIRE 16 -1 (-7475 3875)(-7675 3875);
WIRE 16 -1 (-7475 3775)(-7675 3775);
WIRE 16 -1 (-7475 3725)(-7675 3725);
WIRE 16 -1 (-7475 3475)(-7675 3475);
WIRE 16 -1 (-7475 3325)(-7675 3325);
WIRE 16 -1 (-7475 4225)(-8275 4225);
FORCEPROP 2 LAST SIG_NAME M_K_CPU0_SB_CS_N<0>
J 0
(-8225 4235);
DISPLAY 0.489362 (-8225 4235);
WIRE 16 -1 (-7475 4275)(-8275 4275);
FORCEPROP 2 LAST SIG_NAME M_K_CPU0_SB_CS_N<1>
J 0
(-8225 4285);
DISPLAY 0.489362 (-8225 4285);
WIRE 16 -1 (-6075 5325)(-6275 5325);
WIRE 16 -1 (-6075 5275)(-6275 5275);
WIRE 16 -1 (-6075 5225)(-6275 5225);
WIRE 16 -1 (-6275 5175)(-6075 5175);
WIRE 16 -1 (-6075 5125)(-6275 5125);
WIRE 16 -1 (-6075 5075)(-6275 5075);
WIRE 16 -1 (-6075 5025)(-6275 5025);
WIRE 16 -1 (-6275 4975)(-6075 4975);
WIRE 16 -1 (-6075 4925)(-6275 4925);
WIRE 16 -1 (-6075 4875)(-6275 4875);
WIRE 16 -1 (-6075 4825)(-6275 4825);
WIRE 16 -1 (-6275 4775)(-6075 4775);
WIRE 16 -1 (-6075 4725)(-6275 4725);
WIRE 16 -1 (-6075 4675)(-6275 4675);
WIRE 16 -1 (-6075 4625)(-6275 4625);
WIRE 16 -1 (-6275 4575)(-6075 4575);
WIRE 16 -1 (-6075 4525)(-6275 4525);
WIRE 16 -1 (-6075 4475)(-6275 4475);
WIRE 16 -1 (-6075 4425)(-6275 4425);
WIRE 16 -1 (-6275 4375)(-6075 4375);
WIRE 16 -1 (-6075 4325)(-6275 4325);
WIRE 16 -1 (-6075 4275)(-6275 4275);
WIRE 16 -1 (-6075 4225)(-6275 4225);
WIRE 16 -1 (-6275 4175)(-6075 4175);
WIRE 16 -1 (-6075 4125)(-6275 4125);
WIRE 16 -1 (-6075 4075)(-6275 4075);
WIRE 16 -1 (-6075 4025)(-6275 4025);
WIRE 16 -1 (-6275 3975)(-6075 3975);
WIRE 16 -1 (-6075 3925)(-6275 3925);
WIRE 16 -1 (-6075 3875)(-6275 3875);
WIRE 16 -1 (-6075 3825)(-6275 3825);
WIRE 16 -1 (-6275 3725)(-6075 3725);
WIRE 16 -1 (-6075 3675)(-6275 3675);
WIRE 16 -1 (-6075 3625)(-6275 3625);
WIRE 16 -1 (-6075 3575)(-6275 3575);
WIRE 16 -1 (-6075 3475)(-6275 3475);
WIRE 16 -1 (-6075 3375)(-6275 3375);
WIRE 16 -1 (-6275 3325)(-6075 3325);
WIRE 16 -1 (-6075 3275)(-6275 3275);
WIRE 16 -1 (-6075 3225)(-6275 3225);
WIRE 16 -1 (-6075 3175)(-6275 3175);
WIRE 16 -1 (-6275 3125)(-6075 3125);
WIRE 16 -1 (-6075 3075)(-6275 3075);
WIRE 16 -1 (-6075 3025)(-6275 3025);
WIRE 16 -1 (-6075 2975)(-6275 2975);
WIRE 16 -1 (-6275 2925)(-6075 2925);
WIRE 16 -1 (-6075 2875)(-6275 2875);
WIRE 16 -1 (-6075 2825)(-6275 2825);
WIRE 16 -1 (-6075 2775)(-6275 2775);
WIRE 16 -1 (-6275 2725)(-6075 2725);
WIRE 16 -1 (-6075 2675)(-6275 2675);
WIRE 16 -1 (-6075 2625)(-6275 2625);
WIRE 16 -1 (-6075 2575)(-6275 2575);
WIRE 16 -1 (-6275 2525)(-6075 2525);
WIRE 16 -1 (-6075 2475)(-6275 2475);
WIRE 16 -1 (-6075 2425)(-6275 2425);
WIRE 16 -1 (-6075 2375)(-6275 2375);
WIRE 16 -1 (-6275 2325)(-6075 2325);
WIRE 16 -1 (-6075 2275)(-6275 2275);
WIRE 16 -1 (-6075 2225)(-6275 2225);
WIRE 16 -1 (-6075 2175)(-6275 2175);
WIRE 16 -1 (-7475 4575)(-8275 4575);
FORCEPROP 2 LAST SIG_NAME M_K_CPU0_SA_PAR
J 0
(-8225 4585);
DISPLAY 0.489362 (-8225 4585);
WIRE 16 -1 (-7475 4525)(-8275 4525);
FORCEPROP 2 LAST SIG_NAME M_K_CPU0_SB_PAR
J 0
(-8225 4535);
DISPLAY 0.489362 (-8225 4535);
WIRE 16 -1 (-3675 4350)(-3325 4350);
WIRE 16 -1 (-3525 4300)(-3675 4300);
WIRE 16 -1 (-3525 3450)(-3675 3450);
WIRE 16 -1 (-3675 3400)(-3325 3400);
WIRE 16 -1 (-3525 3350)(-3675 3350);
WIRE 16 -1 (-3675 3650)(-3325 3650);
WIRE 16 -1 (-3525 3700)(-3675 3700);
WIRE 16 -1 (-3675 2600)(-3325 2600);
WIRE 16 -1 (-3525 2650)(-3675 2650);
WIRE 16 -1 (-3675 3750)(-3325 3750);
WIRE 16 -1 (-3675 3800)(-3525 3800);
WIRE 16 -1 (-3675 2700)(-3325 2700);
WIRE 16 -1 (-3675 2750)(-3525 2750);
WIRE 16 -1 (-3675 3850)(-3325 3850);
WIRE 16 -1 (-3525 3900)(-3675 3900);
WIRE 16 -1 (-3675 2800)(-3325 2800);
WIRE 16 -1 (-3525 2850)(-3675 2850);
WIRE 16 -1 (-3675 3950)(-3325 3950);
WIRE 16 -1 (-3525 4000)(-3675 4000);
WIRE 16 -1 (-3675 2900)(-3325 2900);
WIRE 16 -1 (-3525 2950)(-3675 2950);
WIRE 16 -1 (-3675 4050)(-3325 4050);
WIRE 16 -1 (-3525 4100)(-3675 4100);
WIRE 16 -1 (-3675 3000)(-3325 3000);
WIRE 16 -1 (-3525 3050)(-3675 3050);
WIRE 16 -1 (-3675 4150)(-3325 4150);
WIRE 16 -1 (-3675 4200)(-3525 4200);
WIRE 16 -1 (-3675 3100)(-3325 3100);
WIRE 16 -1 (-3675 3150)(-3525 3150);
WIRE 16 -1 (-3675 4250)(-3325 4250);
WIRE 16 -1 (-3675 3200)(-3325 3200);
WIRE 16 -1 (-3525 3250)(-3675 3250);
WIRE 16 -1 (-3525 4400)(-3675 4400);
WIRE 16 -1 (-3675 3300)(-3325 3300);
WIRE 16 -1 (-3675 4450)(-3325 4450);
WIRE 16 -1 (-3525 4500)(-3675 4500);
WIRE 16 -1 (-3675 4550)(-3325 4550);
WIRE 16 -1 (-3675 4600)(-3525 4600);
WIRE 16 -1 (-3675 3500)(-3325 3500);
WIRE 16 -1 (-3675 3550)(-3525 3550);
WIRE 16 -1 (-7475 5225)(-7675 5225);
WIRE 16 -1 (-7475 5275)(-7675 5275);
WIRE 16 -1 (-7475 5325)(-7675 5325);
WIRE 16 -1 (-7475 5375)(-7675 5375);
WIRE 16 -1 (-7475 4425)(-8275 4425);
FORCEPROP 2 LAST SIG_NAME M_K_CPU0_SA_CS_N<1>
J 0
(-8225 4435);
DISPLAY 0.489362 (-8225 4435);
WIRE 16 -1 (-7475 4375)(-8275 4375);
FORCEPROP 2 LAST SIG_NAME M_K_CPU0_SA_CS_N<0>
J 0
(-8225 4385);
DISPLAY 0.489362 (-8225 4385);
WIRE 16 -1 (-7475 1925)(-8275 1925);
FORCEPROP 2 LAST SIG_NAME M_K_CPU0_SB_RSP<0>
J 0
(-8225 1935);
DISPLAY 0.489362 (-8225 1935);
WIRE 16 -1 (-7475 4125)(-8275 4125);
FORCEPROP 2 LAST SIG_NAME M_K_CPU0_CLK_DP<0>
J 0
(-8225 4135);
DISPLAY 0.489362 (-8225 4135);
WIRE 16 -1 (-7475 4075)(-8275 4075);
FORCEPROP 2 LAST SIG_NAME M_K_CPU0_CLK_DN<0>
J 0
(-8225 4085);
DISPLAY 0.489362 (-8225 4085);
WIRE 16 -1 (-7475 1975)(-8275 1975);
FORCEPROP 2 LAST SIG_NAME M_K_CPU0_SA_RSP<0>
J 0
(-8225 1985);
DISPLAY 0.489362 (-8225 1985);
WIRE 16 -1 (-8975 2125)(-8575 2125);
FORCEPROP 2 LAST SIG_NAME PWRGD_CHGL_CPU0
J 0
(-8960 2135);
DISPLAY 0.489362 (-8960 2135);
DOT 1 (-2250 6200);
DOT 1 (-2825 6200);
DOT 1 (-2825 5775);
DOT 1 (-8350 2125);
DOT 1 (-2125 2175);
DOT 1 (-2125 2125);
DOT 1 (-2125 2075);
DOT 1 (-2125 2325);
DOT 1 (-2125 2275);
DOT 1 (-2125 2425);
DOT 1 (-2125 2225);
DOT 1 (-2125 2375);
DOT 1 (-2125 2475);
DOT 1 (-2125 2625);
DOT 1 (-2125 2575);
DOT 1 (-2125 2525);
DOT 1 (-2125 2675);
DOT 1 (-2125 2725);
DOT 1 (-2125 2825);
DOT 1 (-2125 2775);
DOT 1 (-2125 2925);
DOT 1 (-2125 2975);
DOT 1 (-2125 2875);
DOT 1 (-2125 3125);
DOT 1 (-2125 3075);
DOT 1 (-2125 3025);
DOT 1 (-2125 3225);
DOT 1 (-2125 3175);
DOT 1 (-2125 3375);
DOT 1 (-2125 3325);
DOT 1 (-2125 3275);
DOT 1 (-2125 3475);
DOT 1 (-2125 3425);
DOT 1 (-2125 3625);
DOT 1 (-2125 3575);
DOT 1 (-2125 3525);
DOT 1 (-2125 3725);
DOT 1 (-2125 3675);
DOT 1 (-325 2175);
DOT 1 (-325 2075);
DOT 1 (-325 2025);
DOT 1 (-325 1975);
DOT 1 (-325 2325);
DOT 1 (-325 2275);
DOT 1 (-325 2225);
DOT 1 (-325 2425);
DOT 1 (-325 2375);
DOT 1 (-325 2475);
DOT 1 (-325 2625);
DOT 1 (-325 2575);
DOT 1 (-325 2525);
DOT 1 (-325 2675);
DOT 1 (-325 2725);
DOT 1 (-325 2825);
DOT 1 (-325 2775);
DOT 1 (-325 2925);
DOT 1 (-325 2975);
DOT 1 (-325 2875);
DOT 1 (-325 3175);
DOT 1 (-325 3075);
DOT 1 (-325 3025);
DOT 1 (-325 3225);
DOT 1 (-325 3125);
DOT 1 (-325 3425);
DOT 1 (-325 3325);
DOT 1 (-325 3275);
DOT 1 (-325 3475);
DOT 1 (-325 3375);
DOT 1 (-325 3625);
DOT 1 (-325 3575);
DOT 1 (-325 3525);
DOT 1 (-325 3725);
DOT 1 (-325 3675);
DOT 1 (-2125 3925);
DOT 1 (-2125 3825);
DOT 1 (-2125 3775);
DOT 1 (-2125 3975);
DOT 1 (-2125 3875);
DOT 1 (-2125 4125);
DOT 1 (-2125 4075);
DOT 1 (-2125 4025);
DOT 1 (-2125 4225);
DOT 1 (-2125 4175);
DOT 1 (-2125 4375);
DOT 1 (-2125 4325);
DOT 1 (-2125 4275);
DOT 1 (-2125 4475);
DOT 1 (-2125 4425);
DOT 1 (-2125 4525);
DOT 1 (-2125 4675);
DOT 1 (-2125 4625);
DOT 1 (-2125 4575);
DOT 1 (-2125 4725);
DOT 1 (-2125 4775);
DOT 1 (-2125 4875);
DOT 1 (-2125 4825);
DOT 1 (-2125 4975);
DOT 1 (-2125 5025);
DOT 1 (-2125 4925);
DOT 1 (-2125 5125);
DOT 1 (-2125 5075);
DOT 1 (-2125 5275);
DOT 1 (-2125 5325);
DOT 1 (-325 3875);
DOT 1 (-325 3825);
DOT 1 (-325 3775);
DOT 1 (-325 3975);
DOT 1 (-325 3925);
DOT 1 (-325 4125);
DOT 1 (-325 4075);
DOT 1 (-325 4025);
DOT 1 (-325 4225);
DOT 1 (-325 4375);
DOT 1 (-325 4275);
DOT 1 (-325 4325);
DOT 1 (-325 4475);
DOT 1 (-325 4425);
DOT 1 (-325 4525);
DOT 1 (-325 4675);
DOT 1 (-325 4625);
DOT 1 (-325 4575);
DOT 1 (-325 4725);
DOT 1 (-325 4775);
DOT 1 (-325 4875);
DOT 1 (-325 4825);
DOT 1 (-325 4975);
DOT 1 (-325 5025);
DOT 1 (-325 4925);
DOT 1 (-325 5225);
DOT 1 (-325 5125);
DOT 1 (-325 5075);
DOT 1 (-325 5275);
DOT 1 (-325 5175);
DOT 1 (-325 4175);
DOT 1 (-8500 3325);
QUIT
